FILE_TYPE = MACRO_DRAWING;
SET COLOR_WIRE YELLOW;
SET COLOR_PROP MONO;
SET COLOR_DOT WHITE;
SET COLOR_ARC YELLOW;
SET COLOR_BODY GREEN;
SET COLOR_NOTE MONO;
SET PROP_DISPLAY VALUE;
SET PAGE_NUMBER P125;
FORCEADD RES..2
(1750 3050);
FORCEPROP 1 LAST PART_NUMBER G21796-026
J 0
(1790 2925);
DISPLAY 0.617021 (1790 2925);
PAINT BLUE (1790 2925);
FORCEPROP 1 LAST LOCATION R2R11
J 0
(1795 3175);
DISPLAY 0.617021 (1795 3175);
PAINT AQUA (1795 3175);
FORCEPROP 1 LAST TOLERANCE 1%
J 0
(1795 3075);
DISPLAY 0.617021 (1795 3075);
PAINT SKYBLUE (1795 3075);
FORCEPROP 1 LASTPIN (1750 3150) $PN 1
J 0
(1755 3112);
DISPLAY 0.617021 (1755 3112);
PAINT WHITE (1755 3112);
FORCEPROP 1 LAST MATERIAL EMPTY
J 0
(1790 2975);
DISPLAY 0.617021 (1790 2975);
PAINT RED (1790 2975);
FORCEPROP 1 LAST WATTAGE 1/16W
J 0
(1790 3025);
DISPLAY 0.617021 (1790 3025);
PAINT SKYBLUE (1790 3025);
FORCEPROP 1 LASTPIN (1750 2950) $PN 2
J 0
(1755 2960);
DISPLAY 0.617021 (1755 2960);
PAINT WHITE (1755 2960);
FORCEPROP 1 LAST PACK_TYPE 0402
J 0
(1790 2875);
DISPLAY 0.617021 (1790 2875);
PAINT SKYBLUE (1790 2875);
FORCEPROP 1 LAST VALUE 1.00K
J 0
(1795 3125);
DISPLAY 0.617021 (1795 3125);
PAINT SKYBLUE (1795 3125);
FORCEPROP 2 LAST BOM_COST SB
J 0
(1800 3225);
DISPLAY 1.361702 (1800 3225);
PAINT ORANGE (1800 3225);
DISPLAY INVISIBLE (1800 3225);
FORCEPROP 2 LAST CDS_SEC 1
J 0
(1800 3275);
DISPLAY 1.361702 (1800 3275);
PAINT ORANGE (1800 3275);
DISPLAY INVISIBLE (1800 3275);
FORCEPROP 2 LAST $SEC 1
J 0
(1800 3275);
DISPLAY 0.914894 (1800 3275);
PAINT MONO (1800 3275);
DISPLAY INVISIBLE (1800 3275);
FORCEPROP 2 LAST CDS_LOCATION R2R11
J 0
(1795 3175);
DISPLAY 0.617021 (1795 3175);
PAINT AQUA (1795 3175);
DISPLAY INVISIBLE (1795 3175);
FORCEPROP 1 LAST PATH I11
J 0
(1800 3225);
DISPLAY 0.978723 (1800 3225);
PAINT WHITE (1800 3225);
DISPLAY INVISIBLE (1800 3225);
FORCEPROP 2 LAST ROOM SB
J 0
(1800 3225);
DISPLAY 1.361702 (1800 3225);
PAINT ORANGE (1800 3225);
DISPLAY INVISIBLE (1800 3225);
FORCEPROP 2 LAST CDS_LIB mstr_discrete
J 0
(1750 3050);
PAINT ORANGE (1750 3050);
DISPLAY INVISIBLE (1750 3050);
FORCEADD GND..1
(1750 2800);
FORCEPROP 3 LASTPIN (1750 2850) SIG_NAME GND\g
J 0
(1760 2860);
DISPLAY 0.659574 (1760 2860);
PAINT MONO (1760 2860);
DISPLAY INVISIBLE (1760 2860);
FORCEPROP 1 LAST SIZE 1B
J 0
(1825 2750);
DISPLAY 1.170213 (1825 2750);
PAINT AQUA (1825 2750);
DISPLAY INVISIBLE (1825 2750);
FORCEPROP 1 LAST PATH I14
J 0
(1825 2800);
DISPLAY 0.872340 (1825 2800);
PAINT AQUA (1825 2800);
DISPLAY INVISIBLE (1825 2800);
FORCEPROP 2 LAST BOM_COST SB
J 0
(1775 2875);
DISPLAY 1.361702 (1775 2875);
PAINT ORANGE (1775 2875);
DISPLAY INVISIBLE (1775 2875);
FORCEPROP 2 LAST ROOM SB
J 0
(1775 2875);
DISPLAY 1.361702 (1775 2875);
PAINT ORANGE (1775 2875);
DISPLAY INVISIBLE (1775 2875);
FORCEPROP 2 LAST CDS_LIB mstr_symbols
J 0
(1750 2800);
PAINT ORANGE (1750 2800);
DISPLAY INVISIBLE (1750 2800);
FORCEPROP 1 LAST VOLTAGE 0.0V
J 0
(1705 2757);
DISPLAY 0.340426 (1705 2757);
PAINT SKYBLUE (1705 2757);
DISPLAY INVISIBLE (1705 2757);
FORCEPROP 1 LAST BODY_TYPE PLUMBING
J 0
(1705 2757);
DISPLAY 0.340426 (1705 2757);
PAINT GREEN (1705 2757);
DISPLAY INVISIBLE (1705 2757);
FORCEPROP 1 LAST HDL_POWER GND
J 0
(1750 2950);
DISPLAY 1.170213 (1750 2950);
PAINT GREEN (1750 2950);
DISPLAY INVISIBLE (1750 2950);
FORCEADD GND..1
(1850 1225);
FORCEPROP 3 LASTPIN (1850 1275) SIG_NAME GND\g
J 0
(1860 1285);
DISPLAY 0.659574 (1860 1285);
PAINT MONO (1860 1285);
DISPLAY INVISIBLE (1860 1285);
FORCEPROP 2 LAST BOM_COST SB
J 0
(1875 1300);
DISPLAY 1.361702 (1875 1300);
PAINT ORANGE (1875 1300);
DISPLAY INVISIBLE (1875 1300);
FORCEPROP 2 LAST ROOM SB
J 0
(1875 1300);
DISPLAY 1.361702 (1875 1300);
PAINT ORANGE (1875 1300);
DISPLAY INVISIBLE (1875 1300);
FORCEPROP 1 LAST VOLTAGE 0.0V
J 0
(1805 1182);
DISPLAY 0.340426 (1805 1182);
PAINT SKYBLUE (1805 1182);
DISPLAY INVISIBLE (1805 1182);
FORCEPROP 2 LAST CDS_LIB mstr_symbols
J 0
(1850 1225);
PAINT ORANGE (1850 1225);
DISPLAY INVISIBLE (1850 1225);
FORCEPROP 1 LAST SIZE 1B
J 0
(1925 1175);
DISPLAY 1.170213 (1925 1175);
PAINT AQUA (1925 1175);
DISPLAY INVISIBLE (1925 1175);
FORCEPROP 1 LAST PATH I16
J 0
(1925 1225);
DISPLAY 0.872340 (1925 1225);
PAINT AQUA (1925 1225);
DISPLAY INVISIBLE (1925 1225);
FORCEPROP 1 LAST BODY_TYPE PLUMBING
J 0
(1805 1182);
DISPLAY 0.340426 (1805 1182);
PAINT GREEN (1805 1182);
DISPLAY INVISIBLE (1805 1182);
FORCEPROP 1 LAST HDL_POWER GND
J 0
(1850 1375);
DISPLAY 1.170213 (1850 1375);
PAINT GREEN (1850 1375);
DISPLAY INVISIBLE (1850 1375);
FORCEADD OFFPAGE..5
(650 3275);
FORCEPROP 2 LAST $XR2 154 
J 0
(125 3275);
DISPLAY 0.638298 (125 3275);
PAINT MONO (125 3275);
FORCEPROP 2 LAST $XR1 121 
J 0
(245 3275);
DISPLAY 0.638298 (245 3275);
PAINT MONO (245 3275);
FORCEPROP 2 LAST $XR0 111 
J 0
(365 3275);
DISPLAY 0.638298 (365 3275);
PAINT MONO (365 3275);
FORCEPROP 2 LAST CDS_LIB mstr_standard
J 0
(650 3275);
PAINT ORANGE (650 3275);
DISPLAY INVISIBLE (650 3275);
FORCEPROP 2 LAST BOM_COST SB
J 0
(375 3325);
DISPLAY 1.361702 (375 3325);
PAINT ORANGE (375 3325);
DISPLAY INVISIBLE (375 3325);
FORCEPROP 2 LAST ROOM SB
J 0
(375 3325);
DISPLAY 1.361702 (375 3325);
PAINT ORANGE (375 3325);
DISPLAY INVISIBLE (375 3325);
FORCEPROP 2 LAST PATH I20
J 0
(375 3325);
DISPLAY 1.021277 (375 3325);
PAINT ORANGE (375 3325);
DISPLAY INVISIBLE (375 3325);
FORCEPROP 1 LAST OFFPAGE TRUE
J 0
(975 3150);
DISPLAY 1.170213 (975 3150);
PAINT GREEN (975 3150);
DISPLAY INVISIBLE (975 3150);
FORCEPROP 1 LAST COMMENT_BODY TRUE
J 0
(750 3200);
DISPLAY 1.170213 (750 3200);
PAINT GREEN (750 3200);
DISPLAY INVISIBLE (750 3200);
FORCEADD RES..2
(-950 3150);
FORCEPROP 1 LAST LOCATION R8E6
J 0
(-905 3275);
DISPLAY 0.617021 (-905 3275);
PAINT AQUA (-905 3275);
FORCEPROP 1 LAST VALUE 1.00K
J 0
(-905 3225);
DISPLAY 0.617021 (-905 3225);
PAINT SKYBLUE (-905 3225);
FORCEPROP 1 LAST TOLERANCE 1%
J 0
(-905 3175);
DISPLAY 0.617021 (-905 3175);
PAINT SKYBLUE (-905 3175);
FORCEPROP 1 LASTPIN (-950 3250) $PN 1
J 0
(-945 3212);
DISPLAY 0.617021 (-945 3212);
PAINT ORANGE (-945 3212);
FORCEPROP 1 LASTPIN (-950 3050) $PN 2
J 0
(-945 3060);
DISPLAY 0.617021 (-945 3060);
PAINT ORANGE (-945 3060);
FORCEPROP 1 LAST WATTAGE 1/16W
J 0
(-910 3125);
DISPLAY 0.617021 (-910 3125);
PAINT SKYBLUE (-910 3125);
FORCEPROP 1 LAST MATERIAL EMPTY
J 0
(-910 3075);
DISPLAY 0.617021 (-910 3075);
PAINT RED (-910 3075);
FORCEPROP 1 LAST PACK_TYPE 0402
J 0
(-910 2975);
DISPLAY 0.617021 (-910 2975);
PAINT SKYBLUE (-910 2975);
FORCEPROP 1 LAST PART_NUMBER G21796-026
J 0
(-910 3025);
DISPLAY 0.617021 (-910 3025);
PAINT BLUE (-910 3025);
FORCEPROP 2 LAST SEC_TYPE 0402
J 0
(-900 3375);
DISPLAY 1.021277 (-900 3375);
PAINT ORANGE (-900 3375);
DISPLAY INVISIBLE (-900 3375);
FORCEPROP 2 LAST SEC 1
J 0
(-900 3375);
DISPLAY 0.680851 (-900 3375);
PAINT MONO (-900 3375);
DISPLAY INVISIBLE (-900 3375);
FORCEPROP 2 LAST BOM_COST SB
J 0
(-900 3325);
DISPLAY 1.361702 (-900 3325);
PAINT ORANGE (-900 3325);
DISPLAY INVISIBLE (-900 3325);
FORCEPROP 1 LAST PATH I21
J 0
(-900 3325);
DISPLAY 0.978723 (-900 3325);
PAINT WHITE (-900 3325);
DISPLAY INVISIBLE (-900 3325);
FORCEPROP 2 LAST ROOM SB
J 0
(-900 3325);
DISPLAY 1.361702 (-900 3325);
PAINT ORANGE (-900 3325);
DISPLAY INVISIBLE (-900 3325);
FORCEPROP 2 LAST CDS_LOCATION R8E6
J 0
(-905 3275);
DISPLAY 0.617021 (-905 3275);
PAINT AQUA (-905 3275);
DISPLAY INVISIBLE (-905 3275);
FORCEPROP 2 LAST CDS_LIB mstr_discrete
J 0
(-950 3150);
PAINT ORANGE (-950 3150);
DISPLAY INVISIBLE (-950 3150);
FORCEADD OFFPAGE..5
(925 1700);
FORCEPROP 2 LAST $XR1 154 
J 0
(550 1700);
DISPLAY 0.638298 (550 1700);
PAINT MONO (550 1700);
FORCEPROP 2 LAST $XR0 121 
J 0
(670 1700);
DISPLAY 0.638298 (670 1700);
PAINT MONO (670 1700);
FORCEPROP 2 LAST CDS_LIB mstr_standard
J 0
(925 1700);
PAINT ORANGE (925 1700);
DISPLAY INVISIBLE (925 1700);
FORCEPROP 2 LAST ROOM SB
J 0
(650 1750);
DISPLAY 1.361702 (650 1750);
PAINT ORANGE (650 1750);
DISPLAY INVISIBLE (650 1750);
FORCEPROP 2 LAST BOM_COST SB
J 0
(650 1750);
DISPLAY 1.361702 (650 1750);
PAINT ORANGE (650 1750);
DISPLAY INVISIBLE (650 1750);
FORCEPROP 2 LAST PATH I23
J 0
(650 1800);
DISPLAY 1.021277 (650 1800);
PAINT ORANGE (650 1800);
DISPLAY INVISIBLE (650 1800);
FORCEPROP 1 LAST OFFPAGE TRUE
J 0
(1250 1575);
DISPLAY 1.170213 (1250 1575);
PAINT GREEN (1250 1575);
DISPLAY INVISIBLE (1250 1575);
FORCEPROP 1 LAST COMMENT_BODY TRUE
J 0
(1025 1625);
DISPLAY 1.170213 (1025 1625);
PAINT GREEN (1025 1625);
DISPLAY INVISIBLE (1025 1625);
FORCEADD RES..2
(-950 2750);
FORCEPROP 1 LAST WATTAGE 1/16W
J 0
(-910 2725);
DISPLAY 0.617021 (-910 2725);
PAINT SKYBLUE (-910 2725);
FORCEPROP 1 LASTPIN (-950 2850) $PN 1
J 0
(-945 2812);
DISPLAY 0.617021 (-945 2812);
PAINT WHITE (-945 2812);
FORCEPROP 1 LAST TOLERANCE 1%
J 0
(-905 2775);
DISPLAY 0.617021 (-905 2775);
PAINT SKYBLUE (-905 2775);
FORCEPROP 1 LASTPIN (-950 2650) $PN 2
J 0
(-945 2660);
DISPLAY 0.617021 (-945 2660);
PAINT WHITE (-945 2660);
FORCEPROP 1 LAST LOCATION R8E4
J 0
(-905 2875);
DISPLAY 0.617021 (-905 2875);
PAINT AQUA (-905 2875);
FORCEPROP 1 LAST VALUE 1.00K
J 0
(-905 2825);
DISPLAY 0.617021 (-905 2825);
PAINT SKYBLUE (-905 2825);
FORCEPROP 1 LAST MATERIAL EMPTY
J 0
(-910 2675);
DISPLAY 0.617021 (-910 2675);
PAINT RED (-910 2675);
FORCEPROP 1 LAST PACK_TYPE 0402
J 0
(-910 2575);
DISPLAY 0.617021 (-910 2575);
PAINT SKYBLUE (-910 2575);
FORCEPROP 1 LAST PART_NUMBER G21796-026
J 0
(-910 2625);
DISPLAY 0.617021 (-910 2625);
PAINT BLUE (-910 2625);
FORCEPROP 2 LAST $SEC 1
J 0
(-900 2975);
DISPLAY 0.914894 (-900 2975);
PAINT MONO (-900 2975);
DISPLAY INVISIBLE (-900 2975);
FORCEPROP 2 LAST CDS_SEC 1
J 0
(-900 2975);
DISPLAY 1.361702 (-900 2975);
PAINT ORANGE (-900 2975);
DISPLAY INVISIBLE (-900 2975);
FORCEPROP 2 LAST BOM_COST SB
J 0
(-900 2925);
DISPLAY 1.361702 (-900 2925);
PAINT ORANGE (-900 2925);
DISPLAY INVISIBLE (-900 2925);
FORCEPROP 1 LAST PATH I24
J 0
(-900 2925);
DISPLAY 0.978723 (-900 2925);
PAINT WHITE (-900 2925);
DISPLAY INVISIBLE (-900 2925);
FORCEPROP 2 LAST ROOM SB
J 0
(-900 2925);
DISPLAY 1.361702 (-900 2925);
PAINT ORANGE (-900 2925);
DISPLAY INVISIBLE (-900 2925);
FORCEPROP 2 LAST CDS_LOCATION R8E4
J 0
(-905 2875);
DISPLAY 0.617021 (-905 2875);
PAINT AQUA (-905 2875);
DISPLAY INVISIBLE (-905 2875);
FORCEPROP 2 LAST CDS_LIB mstr_discrete
J 0
(-950 2750);
PAINT ORANGE (-950 2750);
DISPLAY INVISIBLE (-950 2750);
FORCEADD GND..1
(-950 2500);
FORCEPROP 3 LASTPIN (-950 2550) SIG_NAME GND\g
J 0
(-940 2560);
DISPLAY 0.659574 (-940 2560);
PAINT MONO (-940 2560);
DISPLAY INVISIBLE (-940 2560);
FORCEPROP 2 LAST ROOM SB
J 0
(-925 2575);
DISPLAY 1.361702 (-925 2575);
PAINT ORANGE (-925 2575);
DISPLAY INVISIBLE (-925 2575);
FORCEPROP 2 LAST BOM_COST SB
J 0
(-925 2575);
DISPLAY 1.361702 (-925 2575);
PAINT ORANGE (-925 2575);
DISPLAY INVISIBLE (-925 2575);
FORCEPROP 1 LAST VOLTAGE 0.0V
J 0
(-995 2457);
DISPLAY 0.340426 (-995 2457);
PAINT SKYBLUE (-995 2457);
DISPLAY INVISIBLE (-995 2457);
FORCEPROP 1 LAST SIZE 1B
J 0
(-875 2450);
DISPLAY 1.170213 (-875 2450);
PAINT AQUA (-875 2450);
DISPLAY INVISIBLE (-875 2450);
FORCEPROP 2 LAST CDS_LIB mstr_symbols
J 0
(-950 2500);
PAINT ORANGE (-950 2500);
DISPLAY INVISIBLE (-950 2500);
FORCEPROP 1 LAST PATH I25
J 0
(-875 2500);
DISPLAY 0.872340 (-875 2500);
PAINT AQUA (-875 2500);
DISPLAY INVISIBLE (-875 2500);
FORCEPROP 1 LAST BODY_TYPE PLUMBING
J 0
(-995 2457);
DISPLAY 0.340426 (-995 2457);
PAINT GREEN (-995 2457);
DISPLAY INVISIBLE (-995 2457);
FORCEPROP 1 LAST HDL_POWER GND
J 0
(-950 2650);
DISPLAY 1.170213 (-950 2650);
PAINT GREEN (-950 2650);
DISPLAY INVISIBLE (-950 2650);
FORCEADD RES..2
(-3225 2525);
FORCEPROP 1 LAST VALUE 1.00K
J 0
(-3180 2600);
DISPLAY 0.617021 (-3180 2600);
PAINT SKYBLUE (-3180 2600);
FORCEPROP 1 LAST WATTAGE 1/16W
J 0
(-3185 2500);
DISPLAY 0.617021 (-3185 2500);
PAINT SKYBLUE (-3185 2500);
FORCEPROP 1 LAST TOLERANCE 1%
J 0
(-3180 2550);
DISPLAY 0.617021 (-3180 2550);
PAINT SKYBLUE (-3180 2550);
FORCEPROP 1 LASTPIN (-3225 2625) $PN 1
J 0
(-3220 2587);
DISPLAY 0.617021 (-3220 2587);
PAINT WHITE (-3220 2587);
FORCEPROP 1 LAST LOCATION R8C18
J 0
(-3180 2650);
DISPLAY 0.617021 (-3180 2650);
PAINT AQUA (-3180 2650);
FORCEPROP 1 LAST PACK_TYPE 0402
J 0
(-3185 2350);
DISPLAY 0.617021 (-3185 2350);
PAINT SKYBLUE (-3185 2350);
FORCEPROP 1 LASTPIN (-3225 2425) $PN 2
J 0
(-3220 2435);
DISPLAY 0.617021 (-3220 2435);
PAINT WHITE (-3220 2435);
FORCEPROP 1 LAST PART_NUMBER G21796-026
J 0
(-3185 2400);
DISPLAY 0.617021 (-3185 2400);
PAINT BLUE (-3185 2400);
FORCEPROP 1 LAST MATERIAL CHIP
J 0
(-3185 2450);
DISPLAY 0.617021 (-3185 2450);
PAINT SKYBLUE (-3185 2450);
FORCEPROP 2 LAST CDS_SEC 1
J 0
(-3175 2750);
DISPLAY 1.361702 (-3175 2750);
PAINT ORANGE (-3175 2750);
DISPLAY INVISIBLE (-3175 2750);
FORCEPROP 2 LAST BOM_COST SB
J 0
(-3175 2700);
DISPLAY 1.361702 (-3175 2700);
PAINT ORANGE (-3175 2700);
DISPLAY INVISIBLE (-3175 2700);
FORCEPROP 2 LAST $SEC 1
J 0
(-3175 2750);
DISPLAY 0.914894 (-3175 2750);
PAINT MONO (-3175 2750);
DISPLAY INVISIBLE (-3175 2750);
FORCEPROP 2 LAST CDS_LOCATION R8C18
J 0
(-3180 2650);
DISPLAY 0.617021 (-3180 2650);
PAINT AQUA (-3180 2650);
DISPLAY INVISIBLE (-3180 2650);
FORCEPROP 1 LAST PATH I40
J 0
(-3175 2700);
DISPLAY 0.978723 (-3175 2700);
PAINT WHITE (-3175 2700);
DISPLAY INVISIBLE (-3175 2700);
FORCEPROP 2 LAST ROOM SB
J 0
(-3175 2700);
DISPLAY 1.361702 (-3175 2700);
PAINT ORANGE (-3175 2700);
DISPLAY INVISIBLE (-3175 2700);
FORCEPROP 2 LAST CDS_LIB mstr_discrete
J 0
(-3225 2525);
PAINT ORANGE (-3225 2525);
DISPLAY INVISIBLE (-3225 2525);
FORCEADD RES..2
(-3225 2200);
FORCEPROP 1 LAST PART_NUMBER G21796-026
J 0
(-3160 2025);
DISPLAY 0.617021 (-3160 2025);
PAINT BLUE (-3160 2025);
FORCEPROP 1 LAST TOLERANCE 1%
J 0
(-3155 2175);
DISPLAY 0.617021 (-3155 2175);
PAINT SKYBLUE (-3155 2175);
FORCEPROP 1 LASTPIN (-3225 2300) $PN 1
J 0
(-3220 2262);
DISPLAY 0.617021 (-3220 2262);
PAINT ORANGE (-3220 2262);
FORCEPROP 1 LASTPIN (-3225 2100) $PN 2
J 0
(-3220 2110);
DISPLAY 0.617021 (-3220 2110);
PAINT ORANGE (-3220 2110);
FORCEPROP 1 LAST VALUE 1.00K
J 0
(-3155 2225);
DISPLAY 0.617021 (-3155 2225);
PAINT SKYBLUE (-3155 2225);
FORCEPROP 1 LAST MATERIAL EMPTY
J 0
(-3160 2075);
DISPLAY 0.617021 (-3160 2075);
PAINT RED (-3160 2075);
FORCEPROP 1 LAST LOCATION R8C17
J 0
(-3155 2275);
DISPLAY 0.617021 (-3155 2275);
PAINT AQUA (-3155 2275);
FORCEPROP 1 LAST WATTAGE 1/16W
J 0
(-3160 2125);
DISPLAY 0.617021 (-3160 2125);
PAINT SKYBLUE (-3160 2125);
FORCEPROP 1 LAST PACK_TYPE 0402
J 0
(-3035 2175);
DISPLAY 0.617021 (-3035 2175);
PAINT SKYBLUE (-3035 2175);
FORCEPROP 2 LAST ROOM SB
J 0
(-3175 2375);
DISPLAY 1.361702 (-3175 2375);
PAINT ORANGE (-3175 2375);
DISPLAY INVISIBLE (-3175 2375);
FORCEPROP 1 LAST PATH I41
J 0
(-3175 2375);
DISPLAY 0.978723 (-3175 2375);
PAINT WHITE (-3175 2375);
DISPLAY INVISIBLE (-3175 2375);
FORCEPROP 2 LAST SEC 1
J 0
(-3175 2425);
DISPLAY 0.914894 (-3175 2425);
PAINT MONO (-3175 2425);
DISPLAY INVISIBLE (-3175 2425);
FORCEPROP 2 LAST BOM_COST SB
J 0
(-3175 2375);
DISPLAY 1.361702 (-3175 2375);
PAINT ORANGE (-3175 2375);
DISPLAY INVISIBLE (-3175 2375);
FORCEPROP 2 LAST SEC_TYPE 0402
J 0
(-3175 2425);
DISPLAY 1.021277 (-3175 2425);
PAINT ORANGE (-3175 2425);
DISPLAY INVISIBLE (-3175 2425);
FORCEPROP 2 LAST CDS_LOCATION R8C17
J 0
(-3155 2275);
DISPLAY 0.617021 (-3155 2275);
PAINT AQUA (-3155 2275);
DISPLAY INVISIBLE (-3155 2275);
FORCEPROP 2 LAST CDS_LIB mstr_discrete
J 0
(-3225 2200);
PAINT ORANGE (-3225 2200);
DISPLAY INVISIBLE (-3225 2200);
FORCEADD OFFPAGE..5
(-4225 2350);
FORCEPROP 2 LAST $XR1 119 
J 0
(-4600 2350);
DISPLAY 0.638298 (-4600 2350);
PAINT MONO (-4600 2350);
FORCEPROP 2 LAST $XR0 108 
J 0
(-4480 2350);
DISPLAY 0.638298 (-4480 2350);
PAINT MONO (-4480 2350);
FORCEPROP 2 LAST CDS_LIB mstr_standard
J 0
(-4225 2350);
PAINT ORANGE (-4225 2350);
DISPLAY INVISIBLE (-4225 2350);
FORCEPROP 2 LAST BOM_COST SB
J 0
(-4500 2400);
DISPLAY 1.361702 (-4500 2400);
PAINT ORANGE (-4500 2400);
DISPLAY INVISIBLE (-4500 2400);
FORCEPROP 2 LAST ROOM SB
J 0
(-4500 2400);
DISPLAY 1.361702 (-4500 2400);
PAINT ORANGE (-4500 2400);
DISPLAY INVISIBLE (-4500 2400);
FORCEPROP 2 LAST PATH I43
J 0
(-4525 2400);
DISPLAY 1.021277 (-4525 2400);
PAINT ORANGE (-4525 2400);
DISPLAY INVISIBLE (-4525 2400);
FORCEPROP 1 LAST OFFPAGE TRUE
J 0
(-3900 2225);
DISPLAY 1.170213 (-3900 2225);
PAINT GREEN (-3900 2225);
DISPLAY INVISIBLE (-3900 2225);
FORCEPROP 1 LAST COMMENT_BODY TRUE
J 0
(-4125 2275);
DISPLAY 1.170213 (-4125 2275);
PAINT GREEN (-4125 2275);
DISPLAY INVISIBLE (-4125 2275);
FORCEADD P3V3_STBY..1
(-950 3375);
FORCEPROP 3 LASTPIN (-950 3325) SIG_NAME P3V3_STBY\g
J 0
(-940 3335);
DISPLAY 0.659574 (-940 3335);
PAINT MONO (-940 3335);
DISPLAY INVISIBLE (-940 3335);
FORCEPROP 1 LAST VOLTAGE 3.3V
J 0
(-995 3332);
DISPLAY 0.340426 (-995 3332);
PAINT SKYBLUE (-995 3332);
DISPLAY INVISIBLE (-995 3332);
FORCEPROP 2 LAST CDS_LIB mstr_symbols
J 0
(-950 3375);
PAINT ORANGE (-950 3375);
DISPLAY INVISIBLE (-950 3375);
FORCEPROP 1 LAST SIZE 1B
J 0
(-905 3397);
DISPLAY 0.340426 (-905 3397);
PAINT GREEN (-905 3397);
DISPLAY INVISIBLE (-905 3397);
FORCEPROP 1 LAST PATH I48
J 0
(-905 3377);
DISPLAY 0.340426 (-905 3377);
PAINT GREEN (-905 3377);
DISPLAY INVISIBLE (-905 3377);
FORCEPROP 1 LAST BODY_TYPE PLUMBING
J 0
(-995 3332);
DISPLAY 0.340426 (-995 3332);
PAINT GREEN (-995 3332);
DISPLAY INVISIBLE (-995 3332);
FORCEPROP 1 LAST HDL_POWER P3V3_STBY
J 0
(-1250 3250);
DISPLAY 0.872340 (-1250 3250);
PAINT ORANGE (-1250 3250);
DISPLAY INVISIBLE (-1250 3250);
FORCEADD P3V3_STBY..1
(-3225 2750);
FORCEPROP 3 LASTPIN (-3225 2700) SIG_NAME P3V3_STBY\g
J 0
(-3215 2710);
DISPLAY 0.659574 (-3215 2710);
PAINT MONO (-3215 2710);
DISPLAY INVISIBLE (-3215 2710);
FORCEPROP 1 LAST PATH I49
J 0
(-3180 2752);
DISPLAY 0.340426 (-3180 2752);
PAINT GREEN (-3180 2752);
DISPLAY INVISIBLE (-3180 2752);
FORCEPROP 1 LAST SIZE 1B
J 0
(-3180 2772);
DISPLAY 0.340426 (-3180 2772);
PAINT GREEN (-3180 2772);
DISPLAY INVISIBLE (-3180 2772);
FORCEPROP 2 LAST CDS_LIB mstr_symbols
J 0
(-3225 2750);
PAINT ORANGE (-3225 2750);
DISPLAY INVISIBLE (-3225 2750);
FORCEPROP 1 LAST VOLTAGE 3.3V
J 0
(-3270 2707);
DISPLAY 0.340426 (-3270 2707);
PAINT SKYBLUE (-3270 2707);
DISPLAY INVISIBLE (-3270 2707);
FORCEPROP 1 LAST BODY_TYPE PLUMBING
J 0
(-3270 2707);
DISPLAY 0.340426 (-3270 2707);
PAINT GREEN (-3270 2707);
DISPLAY INVISIBLE (-3270 2707);
FORCEPROP 1 LAST HDL_POWER P3V3_STBY
J 0
(-3525 2625);
DISPLAY 0.872340 (-3525 2625);
PAINT ORANGE (-3525 2625);
DISPLAY INVISIBLE (-3525 2625);
FORCEADD RES..2
(-925 4450);
FORCEPROP 1 LAST MATERIAL EMPTY
J 0
(-885 4375);
DISPLAY 0.617021 (-885 4375);
PAINT RED (-885 4375);
FORCEPROP 1 LAST WATTAGE 1/16W
J 0
(-885 4425);
DISPLAY 0.617021 (-885 4425);
PAINT SKYBLUE (-885 4425);
FORCEPROP 1 LAST TOLERANCE 1%
J 0
(-880 4475);
DISPLAY 0.617021 (-880 4475);
PAINT SKYBLUE (-880 4475);
FORCEPROP 1 LAST VALUE 1.00K
J 0
(-880 4525);
DISPLAY 0.617021 (-880 4525);
PAINT SKYBLUE (-880 4525);
FORCEPROP 1 LASTPIN (-925 4550) $PN 1
J 0
(-920 4512);
DISPLAY 0.617021 (-920 4512);
PAINT WHITE (-920 4512);
FORCEPROP 1 LASTPIN (-925 4350) $PN 2
J 0
(-920 4360);
DISPLAY 0.617021 (-920 4360);
PAINT WHITE (-920 4360);
FORCEPROP 1 LAST LOCATION R8D5
J 0
(-880 4575);
DISPLAY 0.617021 (-880 4575);
PAINT AQUA (-880 4575);
FORCEPROP 1 LAST PACK_TYPE 0402
J 0
(-885 4275);
DISPLAY 0.617021 (-885 4275);
PAINT SKYBLUE (-885 4275);
FORCEPROP 1 LAST PART_NUMBER G21796-026
J 0
(-885 4325);
DISPLAY 0.617021 (-885 4325);
PAINT BLUE (-885 4325);
FORCEPROP 2 LAST CDS_LIB mstr_discrete
J 0
(-925 4450);
PAINT ORANGE (-925 4450);
DISPLAY INVISIBLE (-925 4450);
FORCEPROP 2 LAST CDS_LOCATION R8D5
J 0
(-880 4575);
DISPLAY 0.617021 (-880 4575);
PAINT AQUA (-880 4575);
DISPLAY INVISIBLE (-880 4575);
FORCEPROP 2 LAST BOM_COST SB
J 0
(-875 4625);
DISPLAY 1.361702 (-875 4625);
PAINT ORANGE (-875 4625);
DISPLAY INVISIBLE (-875 4625);
FORCEPROP 2 LAST CDS_SEC 1
J 0
(-875 4675);
DISPLAY 1.361702 (-875 4675);
PAINT ORANGE (-875 4675);
DISPLAY INVISIBLE (-875 4675);
FORCEPROP 2 LAST $SEC 1
J 0
(-875 4675);
DISPLAY 0.914894 (-875 4675);
PAINT MONO (-875 4675);
DISPLAY INVISIBLE (-875 4675);
FORCEPROP 2 LAST ROOM SB
J 0
(-875 4625);
DISPLAY 1.361702 (-875 4625);
PAINT ORANGE (-875 4625);
DISPLAY INVISIBLE (-875 4625);
FORCEPROP 1 LAST PATH I50
J 0
(-875 4625);
DISPLAY 0.978723 (-875 4625);
PAINT WHITE (-875 4625);
DISPLAY INVISIBLE (-875 4625);
FORCEADD P3V3_STBY..1
(-925 5100);
FORCEPROP 3 LASTPIN (-925 5050) SIG_NAME P3V3_STBY\g
J 0
(-915 5060);
DISPLAY 0.659574 (-915 5060);
PAINT MONO (-915 5060);
DISPLAY INVISIBLE (-915 5060);
FORCEPROP 1 LAST SIZE 1B
J 0
(-880 5122);
DISPLAY 0.340426 (-880 5122);
PAINT GREEN (-880 5122);
DISPLAY INVISIBLE (-880 5122);
FORCEPROP 2 LAST CDS_LIB mstr_symbols
J 0
(-925 5100);
PAINT ORANGE (-925 5100);
DISPLAY INVISIBLE (-925 5100);
FORCEPROP 1 LAST PATH I51
J 0
(-880 5102);
DISPLAY 0.340426 (-880 5102);
PAINT GREEN (-880 5102);
DISPLAY INVISIBLE (-880 5102);
FORCEPROP 1 LAST VOLTAGE 3.3V
J 0
(-970 5057);
DISPLAY 0.340426 (-970 5057);
PAINT SKYBLUE (-970 5057);
DISPLAY INVISIBLE (-970 5057);
FORCEPROP 1 LAST BODY_TYPE PLUMBING
J 0
(-970 5057);
DISPLAY 0.340426 (-970 5057);
PAINT GREEN (-970 5057);
DISPLAY INVISIBLE (-970 5057);
FORCEPROP 1 LAST HDL_POWER P3V3_STBY
J 0
(-1225 4975);
DISPLAY 0.872340 (-1225 4975);
PAINT ORANGE (-1225 4975);
DISPLAY INVISIBLE (-1225 4975);
FORCEADD OFFPAGE..5
(-1800 4675);
FORCEPROP 2 LAST $XR0 120 
J 0
(-2055 4675);
DISPLAY 0.638298 (-2055 4675);
PAINT MONO (-2055 4675);
FORCEPROP 2 LAST CDS_LIB mstr_standard
J 0
(-1800 4675);
PAINT ORANGE (-1800 4675);
DISPLAY INVISIBLE (-1800 4675);
FORCEPROP 2 LAST PATH I53
J 0
(-2045 4720);
DISPLAY 1.021277 (-2045 4720);
PAINT ORANGE (-2045 4720);
DISPLAY INVISIBLE (-2045 4720);
FORCEPROP 2 LAST ROOM SB
J 0
(-2075 4725);
DISPLAY 1.361702 (-2075 4725);
PAINT ORANGE (-2075 4725);
DISPLAY INVISIBLE (-2075 4725);
FORCEPROP 2 LAST BOM_COST SB
J 0
(-2075 4725);
DISPLAY 1.361702 (-2075 4725);
PAINT ORANGE (-2075 4725);
DISPLAY INVISIBLE (-2075 4725);
FORCEPROP 1 LAST OFFPAGE TRUE
J 0
(-1475 4550);
DISPLAY 1.170213 (-1475 4550);
PAINT GREEN (-1475 4550);
DISPLAY INVISIBLE (-1475 4550);
FORCEPROP 1 LAST COMMENT_BODY TRUE
J 0
(-1700 4600);
DISPLAY 1.170213 (-1700 4600);
PAINT GREEN (-1700 4600);
DISPLAY INVISIBLE (-1700 4600);
FORCEADD GND..1
(-925 4200);
FORCEPROP 3 LASTPIN (-925 4250) SIG_NAME GND\g
J 0
(-915 4260);
DISPLAY 0.659574 (-915 4260);
PAINT MONO (-915 4260);
DISPLAY INVISIBLE (-915 4260);
FORCEPROP 1 LAST SIZE 1B
J 0
(-850 4150);
DISPLAY 1.170213 (-850 4150);
PAINT AQUA (-850 4150);
DISPLAY INVISIBLE (-850 4150);
FORCEPROP 1 LAST PATH I54
J 0
(-850 4200);
DISPLAY 0.872340 (-850 4200);
PAINT AQUA (-850 4200);
DISPLAY INVISIBLE (-850 4200);
FORCEPROP 2 LAST ROOM SB
J 0
(-900 4275);
DISPLAY 1.361702 (-900 4275);
PAINT ORANGE (-900 4275);
DISPLAY INVISIBLE (-900 4275);
FORCEPROP 2 LAST BOM_COST SB
J 0
(-900 4275);
DISPLAY 1.361702 (-900 4275);
PAINT ORANGE (-900 4275);
DISPLAY INVISIBLE (-900 4275);
FORCEPROP 2 LAST CDS_LIB mstr_symbols
J 0
(-925 4200);
PAINT ORANGE (-925 4200);
DISPLAY INVISIBLE (-925 4200);
FORCEPROP 1 LAST VOLTAGE 0.0V
J 0
(-970 4157);
DISPLAY 0.340426 (-970 4157);
PAINT SKYBLUE (-970 4157);
DISPLAY INVISIBLE (-970 4157);
FORCEPROP 1 LAST BODY_TYPE PLUMBING
J 0
(-970 4157);
DISPLAY 0.340426 (-970 4157);
PAINT GREEN (-970 4157);
DISPLAY INVISIBLE (-970 4157);
FORCEPROP 1 LAST HDL_POWER GND
J 0
(-925 4350);
DISPLAY 1.170213 (-925 4350);
PAINT GREEN (-925 4350);
DISPLAY INVISIBLE (-925 4350);
FORCEADD GND..1
(-3225 2000);
FORCEPROP 3 LASTPIN (-3225 2050) SIG_NAME GND\g
J 0
(-3215 2060);
DISPLAY 0.659574 (-3215 2060);
PAINT MONO (-3215 2060);
DISPLAY INVISIBLE (-3215 2060);
FORCEPROP 2 LAST BOM_COST SB
J 0
(-3200 2075);
DISPLAY 1.361702 (-3200 2075);
PAINT ORANGE (-3200 2075);
DISPLAY INVISIBLE (-3200 2075);
FORCEPROP 2 LAST ROOM SB
J 0
(-3200 2075);
DISPLAY 1.361702 (-3200 2075);
PAINT ORANGE (-3200 2075);
DISPLAY INVISIBLE (-3200 2075);
FORCEPROP 1 LAST VOLTAGE 0.0V
J 0
(-3270 1957);
DISPLAY 0.340426 (-3270 1957);
PAINT SKYBLUE (-3270 1957);
DISPLAY INVISIBLE (-3270 1957);
FORCEPROP 2 LAST CDS_LIB mstr_symbols
J 0
(-3225 2000);
PAINT ORANGE (-3225 2000);
DISPLAY INVISIBLE (-3225 2000);
FORCEPROP 1 LAST SIZE 1B
J 0
(-3150 1950);
DISPLAY 1.170213 (-3150 1950);
PAINT AQUA (-3150 1950);
DISPLAY INVISIBLE (-3150 1950);
FORCEPROP 1 LAST PATH I6
J 0
(-3150 2000);
DISPLAY 0.872340 (-3150 2000);
PAINT AQUA (-3150 2000);
DISPLAY INVISIBLE (-3150 2000);
FORCEPROP 1 LAST BODY_TYPE PLUMBING
J 0
(-3270 1957);
DISPLAY 0.340426 (-3270 1957);
PAINT GREEN (-3270 1957);
DISPLAY INVISIBLE (-3270 1957);
FORCEPROP 1 LAST HDL_POWER GND
J 0
(-3225 2150);
DISPLAY 1.170213 (-3225 2150);
PAINT GREEN (-3225 2150);
DISPLAY INVISIBLE (-3225 2150);
FORCEADD RES..2
(-3275 4975);
FORCEPROP 1 LAST MATERIAL EMPTY
J 0
(-3235 4900);
DISPLAY 0.617021 (-3235 4900);
PAINT RED (-3235 4900);
FORCEPROP 1 LAST PACK_TYPE 0402
J 0
(-3235 4800);
DISPLAY 0.617021 (-3235 4800);
PAINT SKYBLUE (-3235 4800);
FORCEPROP 1 LAST LOCATION R7D13
J 0
(-3230 5100);
DISPLAY 0.617021 (-3230 5100);
PAINT AQUA (-3230 5100);
FORCEPROP 1 LAST VALUE 8.2K
J 0
(-3230 5050);
DISPLAY 0.617021 (-3230 5050);
PAINT SKYBLUE (-3230 5050);
FORCEPROP 1 LAST TOLERANCE 1%
J 0
(-3230 5000);
DISPLAY 0.617021 (-3230 5000);
PAINT SKYBLUE (-3230 5000);
FORCEPROP 1 LAST WATTAGE 1/16W
J 0
(-3235 4950);
DISPLAY 0.617021 (-3235 4950);
PAINT SKYBLUE (-3235 4950);
FORCEPROP 1 LAST PART_NUMBER G21796-345
J 0
(-3235 4850);
DISPLAY 0.617021 (-3235 4850);
PAINT BLUE (-3235 4850);
FORCEPROP 2 LAST ROOM SB
J 0
(-3225 5150);
DISPLAY 1.361702 (-3225 5150);
PAINT ORANGE (-3225 5150);
DISPLAY INVISIBLE (-3225 5150);
FORCEPROP 1 LAST PATH I60
J 0
(-3225 5150);
DISPLAY 0.978723 (-3225 5150);
PAINT WHITE (-3225 5150);
DISPLAY INVISIBLE (-3225 5150);
FORCEPROP 2 LAST $SEC 1
J 0
(-3225 5200);
PAINT MONO (-3225 5200);
DISPLAY INVISIBLE (-3225 5200);
FORCEPROP 2 LAST CDS_SEC 1
J 0
(-3225 5200);
DISPLAY 1.361702 (-3225 5200);
PAINT ORANGE (-3225 5200);
DISPLAY INVISIBLE (-3225 5200);
FORCEPROP 2 LAST BOM_COST SB
J 0
(-3225 5150);
DISPLAY 1.361702 (-3225 5150);
PAINT ORANGE (-3225 5150);
DISPLAY INVISIBLE (-3225 5150);
FORCEPROP 2 LAST CDS_LOCATION R7D13
J 0
(-3230 5100);
DISPLAY 0.617021 (-3230 5100);
PAINT AQUA (-3230 5100);
DISPLAY INVISIBLE (-3230 5100);
FORCEPROP 1 LASTPIN (-3275 5075) $PN 1
J 0
(-3270 5037);
DISPLAY 0.787234 (-3270 5037);
PAINT ORANGE (-3270 5037);
DISPLAY INVISIBLE (-3270 5037);
FORCEPROP 2 LAST CDS_LIB mstr_discrete
J 0
(-3275 4975);
PAINT ORANGE (-3275 4975);
DISPLAY INVISIBLE (-3275 4975);
FORCEPROP 1 LASTPIN (-3275 4875) $PN 2
J 0
(-3270 4885);
DISPLAY 0.787234 (-3270 4885);
PAINT ORANGE (-3270 4885);
DISPLAY INVISIBLE (-3270 4885);
FORCEADD P3V3_STBY..1
(-3275 5200);
FORCEPROP 3 LASTPIN (-3275 5150) SIG_NAME P3V3_STBY\g
J 0
(-3265 5160);
DISPLAY 0.659574 (-3265 5160);
PAINT MONO (-3265 5160);
DISPLAY INVISIBLE (-3265 5160);
FORCEPROP 1 LAST PATH I61
J 0
(-3230 5202);
DISPLAY 0.340426 (-3230 5202);
PAINT GREEN (-3230 5202);
DISPLAY INVISIBLE (-3230 5202);
FORCEPROP 2 LAST CDS_LIB mstr_symbols
J 0
(-3275 5200);
PAINT ORANGE (-3275 5200);
DISPLAY INVISIBLE (-3275 5200);
FORCEPROP 1 LAST SIZE 1B
J 0
(-3230 5222);
DISPLAY 0.340426 (-3230 5222);
PAINT GREEN (-3230 5222);
DISPLAY INVISIBLE (-3230 5222);
FORCEPROP 1 LAST VOLTAGE 3.3V
J 0
(-3320 5157);
DISPLAY 0.340426 (-3320 5157);
PAINT SKYBLUE (-3320 5157);
DISPLAY INVISIBLE (-3320 5157);
FORCEPROP 1 LAST BODY_TYPE PLUMBING
J 0
(-3320 5157);
DISPLAY 0.340426 (-3320 5157);
PAINT GREEN (-3320 5157);
DISPLAY INVISIBLE (-3320 5157);
FORCEPROP 1 LAST HDL_POWER P3V3_STBY
J 0
(-3575 5075);
DISPLAY 0.872340 (-3575 5075);
PAINT ORANGE (-3575 5075);
DISPLAY INVISIBLE (-3575 5075);
FORCEADD OFFPAGE..6
(-4075 4800);
FORCEPROP 2 LAST $XR1 147 
J 0
(-4475 4800);
DISPLAY 0.638298 (-4475 4800);
PAINT MONO (-4475 4800);
FORCEPROP 2 LAST $XR0 121 
J 0
(-4355 4800);
DISPLAY 0.638298 (-4355 4800);
PAINT MONO (-4355 4800);
FORCEPROP 2 LAST CDS_LIB mstr_standard
J 0
(-4075 4800);
PAINT ORANGE (-4075 4800);
DISPLAY INVISIBLE (-4075 4800);
FORCEPROP 2 LAST PATH I64
J 0
(-4350 4850);
DISPLAY 1.021277 (-4350 4850);
PAINT ORANGE (-4350 4850);
DISPLAY INVISIBLE (-4350 4850);
FORCEPROP 1 LAST OFFPAGE TRUE
J 0
(-3750 4675);
DISPLAY 1.170213 (-3750 4675);
PAINT GREEN (-3750 4675);
DISPLAY INVISIBLE (-3750 4675);
FORCEPROP 1 LAST COMMENT_BODY TRUE
J 0
(-3975 4725);
DISPLAY 1.170213 (-3975 4725);
PAINT GREEN (-3975 4725);
DISPLAY INVISIBLE (-3975 4725);
FORCEADD OFFPAGE..2
(-3850 3575);
FORCEPROP 2 LAST $XR1 139 
J 0
(-3541 3575);
DISPLAY 0.638298 (-3541 3575);
PAINT MONO (-3541 3575);
FORCEPROP 2 LAST $XR0 121 
J 0
(-3661 3575);
DISPLAY 0.638298 (-3661 3575);
PAINT MONO (-3661 3575);
FORCEPROP 2 LAST PATH I65
J 0
(-3675 3650);
DISPLAY 1.021277 (-3675 3650);
PAINT ORANGE (-3675 3650);
DISPLAY INVISIBLE (-3675 3650);
FORCEPROP 2 LAST CDS_LIB mstr_standard
J 0
(-3850 3575);
PAINT MONO (-3850 3575);
DISPLAY INVISIBLE (-3850 3575);
FORCEPROP 1 LAST OFFPAGE TRUE
J 0
(-3525 3450);
DISPLAY 1.170213 (-3525 3450);
PAINT GREEN (-3525 3450);
DISPLAY INVISIBLE (-3525 3450);
FORCEPROP 1 LAST COMMENT_BODY TRUE
J 0
(-3895 3480);
DISPLAY 1.170213 (-3895 3480);
PAINT GREEN (-3895 3480);
DISPLAY INVISIBLE (-3895 3480);
FORCEADD P3V3_STBY..1
(-5050 3975);
FORCEPROP 3 LASTPIN (-5050 3925) SIG_NAME P3V3_STBY\g
J 0
(-5040 3935);
DISPLAY 0.659574 (-5040 3935);
PAINT MONO (-5040 3935);
DISPLAY INVISIBLE (-5040 3935);
FORCEPROP 2 LAST CDS_LIB mstr_symbols
J 0
(-5050 3975);
PAINT MONO (-5050 3975);
DISPLAY INVISIBLE (-5050 3975);
FORCEPROP 1 LAST SIZE 1B
J 0
(-5005 3997);
DISPLAY 0.340426 (-5005 3997);
PAINT GREEN (-5005 3997);
DISPLAY INVISIBLE (-5005 3997);
FORCEPROP 1 LAST PATH I66
J 0
(-5005 3977);
DISPLAY 0.340426 (-5005 3977);
PAINT GREEN (-5005 3977);
DISPLAY INVISIBLE (-5005 3977);
FORCEPROP 1 LAST VOLTAGE 3.3V
J 0
(-5095 3932);
DISPLAY 0.340426 (-5095 3932);
PAINT SKYBLUE (-5095 3932);
DISPLAY INVISIBLE (-5095 3932);
FORCEPROP 1 LAST BODY_TYPE PLUMBING
J 0
(-5095 3932);
DISPLAY 0.340426 (-5095 3932);
PAINT GREEN (-5095 3932);
DISPLAY INVISIBLE (-5095 3932);
FORCEPROP 1 LAST HDL_POWER P3V3_STBY
J 0
(-5350 3850);
DISPLAY 0.872340 (-5350 3850);
PAINT ORANGE (-5350 3850);
DISPLAY INVISIBLE (-5350 3850);
FORCEADD GND..1
(-5050 3175);
FORCEPROP 3 LASTPIN (-5050 3225) SIG_NAME GND\g
J 0
(-5040 3235);
DISPLAY 0.659574 (-5040 3235);
PAINT MONO (-5040 3235);
DISPLAY INVISIBLE (-5040 3235);
FORCEPROP 1 LAST PATH I69
J 0
(-4975 3175);
DISPLAY 0.872340 (-4975 3175);
PAINT AQUA (-4975 3175);
DISPLAY INVISIBLE (-4975 3175);
FORCEPROP 1 LAST SIZE 1B
J 0
(-4975 3125);
DISPLAY 1.170213 (-4975 3125);
PAINT AQUA (-4975 3125);
DISPLAY INVISIBLE (-4975 3125);
FORCEPROP 2 LAST ROOM SB
J 0
(-5025 3250);
DISPLAY 1.361702 (-5025 3250);
PAINT ORANGE (-5025 3250);
DISPLAY INVISIBLE (-5025 3250);
FORCEPROP 2 LAST BOM_COST SB
J 0
(-5025 3250);
DISPLAY 1.361702 (-5025 3250);
PAINT ORANGE (-5025 3250);
DISPLAY INVISIBLE (-5025 3250);
FORCEPROP 2 LAST CDS_LIB mstr_symbols
J 0
(-5050 3175);
PAINT MONO (-5050 3175);
DISPLAY INVISIBLE (-5050 3175);
FORCEPROP 1 LAST VOLTAGE 0.0V
J 0
(-5095 3132);
DISPLAY 0.340426 (-5095 3132);
PAINT SKYBLUE (-5095 3132);
DISPLAY INVISIBLE (-5095 3132);
FORCEPROP 1 LAST BODY_TYPE PLUMBING
J 0
(-5095 3132);
DISPLAY 0.340426 (-5095 3132);
PAINT GREEN (-5095 3132);
DISPLAY INVISIBLE (-5095 3132);
FORCEPROP 1 LAST HDL_POWER GND
J 0
(-5050 3325);
DISPLAY 1.170213 (-5050 3325);
PAINT GREEN (-5050 3325);
DISPLAY INVISIBLE (-5050 3325);
FORCEADD OFFPAGE..5
(-1450 2975);
FORCEPROP 2 LAST $XR3 184 
J 0
(-2065 2975);
DISPLAY 0.638298 (-2065 2975);
PAINT MONO (-2065 2975);
FORCEPROP 2 LAST $XR2 154 
J 0
(-1945 2975);
DISPLAY 0.638298 (-1945 2975);
PAINT MONO (-1945 2975);
FORCEPROP 2 LAST $XR1 121 
J 0
(-1825 2975);
DISPLAY 0.638298 (-1825 2975);
PAINT MONO (-1825 2975);
FORCEPROP 2 LAST $XR0 111 
J 0
(-1705 2975);
DISPLAY 0.638298 (-1705 2975);
PAINT MONO (-1705 2975);
FORCEPROP 2 LAST ROOM SB
J 0
(-1725 3025);
DISPLAY 1.361702 (-1725 3025);
PAINT ORANGE (-1725 3025);
DISPLAY INVISIBLE (-1725 3025);
FORCEPROP 2 LAST BOM_COST SB
J 0
(-1725 3025);
DISPLAY 1.361702 (-1725 3025);
PAINT ORANGE (-1725 3025);
DISPLAY INVISIBLE (-1725 3025);
FORCEPROP 2 LAST CDS_LIB mstr_standard
J 0
(-1450 2975);
PAINT ORANGE (-1450 2975);
DISPLAY INVISIBLE (-1450 2975);
FORCEPROP 2 LAST PATH I7
J 0
(-1725 3025);
DISPLAY 1.021277 (-1725 3025);
PAINT ORANGE (-1725 3025);
DISPLAY INVISIBLE (-1725 3025);
FORCEPROP 1 LAST OFFPAGE TRUE
J 0
(-1125 2850);
DISPLAY 1.170213 (-1125 2850);
PAINT GREEN (-1125 2850);
DISPLAY INVISIBLE (-1125 2850);
FORCEPROP 1 LAST COMMENT_BODY TRUE
J 0
(-1350 2900);
DISPLAY 1.170213 (-1350 2900);
PAINT GREEN (-1350 2900);
DISPLAY INVISIBLE (-1350 2900);
FORCEADD RES..2
(400 4600);
FORCEPROP 1 LAST LOCATION R3N2
J 0
(445 4725);
DISPLAY 0.617021 (445 4725);
PAINT AQUA (445 4725);
FORCEPROP 1 LAST VALUE 4.75K
J 0
(445 4675);
DISPLAY 0.617021 (445 4675);
PAINT SKYBLUE (445 4675);
FORCEPROP 1 LAST TOLERANCE 1%
J 0
(445 4625);
DISPLAY 0.617021 (445 4625);
PAINT SKYBLUE (445 4625);
FORCEPROP 1 LASTPIN (400 4700) $PN 1
J 0
(405 4662);
DISPLAY 0.617021 (405 4662);
PAINT ORANGE (405 4662);
FORCEPROP 1 LAST PACK_TYPE 0402
J 0
(440 4425);
DISPLAY 0.617021 (440 4425);
PAINT SKYBLUE (440 4425);
FORCEPROP 1 LAST WATTAGE 1/16W
J 0
(440 4575);
DISPLAY 0.617021 (440 4575);
PAINT SKYBLUE (440 4575);
FORCEPROP 1 LAST PART_NUMBER G21796-072
J 0
(440 4475);
DISPLAY 0.617021 (440 4475);
PAINT BLUE (440 4475);
FORCEPROP 1 LAST MATERIAL EMPTY
J 0
(440 4525);
DISPLAY 0.617021 (440 4525);
PAINT RED (440 4525);
FORCEPROP 1 LASTPIN (400 4500) $PN 2
J 0
(405 4510);
DISPLAY 0.617021 (405 4510);
PAINT ORANGE (405 4510);
FORCEPROP 2 LAST SEC_TYPE 0402
J 0
(450 4825);
DISPLAY 1.021277 (450 4825);
PAINT ORANGE (450 4825);
DISPLAY INVISIBLE (450 4825);
FORCEPROP 2 LAST SEC 1
J 0
(450 4825);
DISPLAY 0.680851 (450 4825);
PAINT MONO (450 4825);
DISPLAY INVISIBLE (450 4825);
FORCEPROP 1 LAST PATH I72
J 0
(450 4775);
DISPLAY 0.978723 (450 4775);
PAINT WHITE (450 4775);
DISPLAY INVISIBLE (450 4775);
FORCEPROP 2 LAST CDS_LOCATION R3N2
J 0
(445 4725);
DISPLAY 0.617021 (445 4725);
PAINT AQUA (445 4725);
DISPLAY INVISIBLE (445 4725);
FORCEPROP 2 LAST BOM_COST SB
J 0
(350 4750);
DISPLAY 1.021277 (350 4750);
PAINT ORANGE (350 4750);
DISPLAY INVISIBLE (350 4750);
FORCEPROP 2 LAST ROOM BMC_MISC
J 0
(350 4700);
DISPLAY 1.021277 (350 4700);
PAINT ORANGE (350 4700);
DISPLAY INVISIBLE (350 4700);
FORCEPROP 2 LAST CDS_LIB mstr_discrete
J 0
(400 4600);
PAINT ORANGE (400 4600);
DISPLAY INVISIBLE (400 4600);
FORCEADD OFFPAGE..2
(1550 4325);
FORCEPROP 2 LAST $XR1 121 
J 0
(1859 4325);
DISPLAY 0.638298 (1859 4325);
PAINT MONO (1859 4325);
FORCEPROP 2 LAST $XR0 147 
J 0
(1739 4325);
DISPLAY 0.638298 (1739 4325);
PAINT MONO (1739 4325);
FORCEPROP 2 LAST PATH I73
J 0
(1875 4375);
DISPLAY 1.021277 (1875 4375);
PAINT ORANGE (1875 4375);
DISPLAY INVISIBLE (1875 4375);
FORCEPROP 2 LAST CDS_LIB mstr_standard
J 0
(1550 4325);
PAINT ORANGE (1550 4325);
DISPLAY INVISIBLE (1550 4325);
FORCEPROP 1 LAST OFFPAGE TRUE
J 0
(1875 4200);
DISPLAY 0.872340 (1875 4200);
PAINT GREEN (1875 4200);
DISPLAY INVISIBLE (1875 4200);
FORCEPROP 1 LAST COMMENT_BODY TRUE
J 0
(1505 4230);
DISPLAY 0.872340 (1505 4230);
PAINT GREEN (1505 4230);
DISPLAY INVISIBLE (1505 4230);
FORCEADD P3V3_STBY..1
(400 4900);
FORCEPROP 3 LASTPIN (400 4850) SIG_NAME P3V3_STBY\g
J 0
(410 4860);
DISPLAY 0.659574 (410 4860);
PAINT MONO (410 4860);
DISPLAY INVISIBLE (410 4860);
FORCEPROP 1 LAST SIZE 1B
J 0
(445 4922);
DISPLAY 0.340426 (445 4922);
PAINT GREEN (445 4922);
DISPLAY INVISIBLE (445 4922);
FORCEPROP 2 LAST CDS_LIB mstr_symbols
J 0
(400 4900);
PAINT MONO (400 4900);
DISPLAY INVISIBLE (400 4900);
FORCEPROP 1 LAST PATH I74
J 0
(445 4902);
DISPLAY 0.340426 (445 4902);
PAINT GREEN (445 4902);
DISPLAY INVISIBLE (445 4902);
FORCEPROP 1 LAST VOLTAGE 3.3V
J 0
(355 4857);
DISPLAY 0.340426 (355 4857);
PAINT SKYBLUE (355 4857);
DISPLAY INVISIBLE (355 4857);
FORCEPROP 1 LAST BODY_TYPE PLUMBING
J 0
(355 4857);
DISPLAY 0.340426 (355 4857);
PAINT GREEN (355 4857);
DISPLAY INVISIBLE (355 4857);
FORCEPROP 1 LAST HDL_POWER P3V3_STBY
J 0
(100 4775);
DISPLAY 0.872340 (100 4775);
PAINT ORANGE (100 4775);
DISPLAY INVISIBLE (100 4775);
FORCEADD P3V3_STBY..1
(-3350 1600);
FORCEPROP 3 LASTPIN (-3350 1550) SIG_NAME P3V3_STBY\g
J 0
(-3340 1560);
DISPLAY 0.659574 (-3340 1560);
PAINT MONO (-3340 1560);
DISPLAY INVISIBLE (-3340 1560);
FORCEPROP 1 LAST PATH I75
J 0
(-3305 1602);
DISPLAY 0.340426 (-3305 1602);
PAINT GREEN (-3305 1602);
DISPLAY INVISIBLE (-3305 1602);
FORCEPROP 1 LAST SIZE 1B
J 0
(-3305 1622);
DISPLAY 0.340426 (-3305 1622);
PAINT GREEN (-3305 1622);
DISPLAY INVISIBLE (-3305 1622);
FORCEPROP 2 LAST CDS_LIB mstr_symbols
J 0
(-3350 1600);
PAINT MONO (-3350 1600);
DISPLAY INVISIBLE (-3350 1600);
FORCEPROP 1 LAST VOLTAGE 3.3V
J 0
(-3395 1557);
DISPLAY 0.340426 (-3395 1557);
PAINT SKYBLUE (-3395 1557);
DISPLAY INVISIBLE (-3395 1557);
FORCEPROP 1 LAST BODY_TYPE PLUMBING
J 0
(-3395 1557);
DISPLAY 0.340426 (-3395 1557);
PAINT GREEN (-3395 1557);
DISPLAY INVISIBLE (-3395 1557);
FORCEPROP 1 LAST HDL_POWER P3V3_STBY
J 0
(-3650 1475);
DISPLAY 0.872340 (-3650 1475);
PAINT ORANGE (-3650 1475);
DISPLAY INVISIBLE (-3650 1475);
FORCEADD OFFPAGE..5
(-4075 1175);
FORCEPROP 2 LAST $XR2 191 
J 0
(-4570 1175);
DISPLAY 0.638298 (-4570 1175);
PAINT MONO (-4570 1175);
FORCEPROP 2 LAST $XR1 144 
J 0
(-4450 1175);
DISPLAY 0.638298 (-4450 1175);
PAINT MONO (-4450 1175);
FORCEPROP 2 LAST $XR0 119 
J 0
(-4330 1175);
DISPLAY 0.638298 (-4330 1175);
PAINT MONO (-4330 1175);
FORCEPROP 2 LAST CDS_LIB mstr_standard
J 0
(-4075 1175);
PAINT MONO (-4075 1175);
DISPLAY INVISIBLE (-4075 1175);
FORCEPROP 2 LAST PATH I77
J 0
(-4325 1225);
DISPLAY 1.021277 (-4325 1225);
PAINT ORANGE (-4325 1225);
DISPLAY INVISIBLE (-4325 1225);
FORCEPROP 1 LAST OFFPAGE TRUE
J 0
(-3750 1050);
DISPLAY 0.872340 (-3750 1050);
PAINT GREEN (-3750 1050);
DISPLAY INVISIBLE (-3750 1050);
FORCEPROP 1 LAST COMMENT_BODY TRUE
J 0
(-3975 1100);
DISPLAY 0.872340 (-3975 1100);
PAINT GREEN (-3975 1100);
DISPLAY INVISIBLE (-3975 1100);
FORCEADD RES..2
(1850 1875);
FORCEPROP 1 LAST PACK_TYPE 0402
J 0
(1890 1700);
DISPLAY 0.617021 (1890 1700);
PAINT SKYBLUE (1890 1700);
FORCEPROP 1 LASTPIN (1850 1775) $PN 2
J 0
(1855 1785);
DISPLAY 0.617021 (1855 1785);
PAINT ORANGE (1855 1785);
FORCEPROP 1 LASTPIN (1850 1975) $PN 1
J 0
(1855 1937);
DISPLAY 0.617021 (1855 1937);
PAINT ORANGE (1855 1937);
FORCEPROP 1 LAST TOLERANCE 1%
J 0
(1895 1900);
DISPLAY 0.617021 (1895 1900);
PAINT SKYBLUE (1895 1900);
FORCEPROP 1 LAST LOCATION R3N17
J 0
(1895 2000);
DISPLAY 0.617021 (1895 2000);
PAINT AQUA (1895 2000);
FORCEPROP 1 LAST MATERIAL EMPTY
J 0
(1890 1800);
DISPLAY 0.617021 (1890 1800);
PAINT RED (1890 1800);
FORCEPROP 1 LAST PART_NUMBER G21796-026
J 0
(1890 1750);
DISPLAY 0.617021 (1890 1750);
PAINT BLUE (1890 1750);
FORCEPROP 1 LAST WATTAGE 1/16W
J 0
(1890 1850);
DISPLAY 0.617021 (1890 1850);
PAINT SKYBLUE (1890 1850);
FORCEPROP 1 LAST VALUE 1.00K
J 0
(1895 1950);
DISPLAY 0.617021 (1895 1950);
PAINT SKYBLUE (1895 1950);
FORCEPROP 1 LAST PATH I78
J 0
(1900 2050);
DISPLAY 0.978723 (1900 2050);
PAINT WHITE (1900 2050);
DISPLAY INVISIBLE (1900 2050);
FORCEPROP 2 LAST CDS_LIB mstr_discrete
J 0
(1850 1875);
PAINT ORANGE (1850 1875);
DISPLAY INVISIBLE (1850 1875);
FORCEPROP 2 LAST CDS_LOCATION R3N17
J 0
(1895 2000);
DISPLAY 0.617021 (1895 2000);
PAINT AQUA (1895 2000);
DISPLAY INVISIBLE (1895 2000);
FORCEPROP 2 LAST BOM_COST SB
J 0
(1900 2050);
DISPLAY 1.361702 (1900 2050);
PAINT ORANGE (1900 2050);
DISPLAY INVISIBLE (1900 2050);
FORCEPROP 2 LAST SEC_TYPE 0402
J 0
(1900 2100);
DISPLAY 1.021277 (1900 2100);
PAINT ORANGE (1900 2100);
DISPLAY INVISIBLE (1900 2100);
FORCEPROP 2 LAST SEC 1
J 0
(1900 2100);
DISPLAY 0.680851 (1900 2100);
PAINT MONO (1900 2100);
DISPLAY INVISIBLE (1900 2100);
FORCEPROP 2 LAST ROOM SB
J 0
(1900 2050);
DISPLAY 1.361702 (1900 2050);
PAINT ORANGE (1900 2050);
DISPLAY INVISIBLE (1900 2050);
FORCEADD P3V3_STBY..1
(1850 2125);
FORCEPROP 3 LASTPIN (1850 2075) SIG_NAME P3V3_STBY\g
J 0
(1860 2085);
DISPLAY 0.659574 (1860 2085);
PAINT MONO (1860 2085);
DISPLAY INVISIBLE (1860 2085);
FORCEPROP 1 LAST PATH I79
J 0
(1895 2127);
DISPLAY 0.340426 (1895 2127);
PAINT GREEN (1895 2127);
DISPLAY INVISIBLE (1895 2127);
FORCEPROP 2 LAST CDS_LIB mstr_symbols
J 0
(1850 2125);
PAINT ORANGE (1850 2125);
DISPLAY INVISIBLE (1850 2125);
FORCEPROP 1 LAST SIZE 1B
J 0
(1895 2147);
DISPLAY 0.340426 (1895 2147);
PAINT GREEN (1895 2147);
DISPLAY INVISIBLE (1895 2147);
FORCEPROP 1 LAST VOLTAGE 3.3V
J 0
(1805 2082);
DISPLAY 0.340426 (1805 2082);
PAINT SKYBLUE (1805 2082);
DISPLAY INVISIBLE (1805 2082);
FORCEPROP 1 LAST BODY_TYPE PLUMBING
J 0
(1805 2082);
DISPLAY 0.340426 (1805 2082);
PAINT GREEN (1805 2082);
DISPLAY INVISIBLE (1805 2082);
FORCEPROP 1 LAST HDL_POWER P3V3_STBY
J 0
(1550 2000);
DISPLAY 0.872340 (1550 2000);
PAINT ORANGE (1550 2000);
DISPLAY INVISIBLE (1550 2000);
FORCEADD OFFPAGE..5
(-1975 1350);
FORCEPROP 2 LAST $XR1 176 
J 0
(-2350 1350);
DISPLAY 0.638298 (-2350 1350);
PAINT MONO (-2350 1350);
FORCEPROP 2 LAST $XR0 119 
J 0
(-2230 1350);
DISPLAY 0.638298 (-2230 1350);
PAINT MONO (-2230 1350);
FORCEPROP 2 LAST PATH I82
J 0
(-1925 1425);
DISPLAY 1.021277 (-1925 1425);
PAINT ORANGE (-1925 1425);
DISPLAY INVISIBLE (-1925 1425);
FORCEPROP 2 LAST CDS_LIB mstr_standard
J 0
(-1975 1350);
PAINT ORANGE (-1975 1350);
DISPLAY INVISIBLE (-1975 1350);
FORCEPROP 1 LAST OFFPAGE TRUE
J 0
(-1650 1225);
DISPLAY 0.872340 (-1650 1225);
PAINT GREEN (-1650 1225);
DISPLAY INVISIBLE (-1650 1225);
FORCEPROP 1 LAST COMMENT_BODY TRUE
J 0
(-1875 1275);
DISPLAY 0.872340 (-1875 1275);
PAINT GREEN (-1875 1275);
DISPLAY INVISIBLE (-1875 1275);
FORCEADD RES..2
(-925 1525);
FORCEPROP 1 LAST TOLERANCE 1%
J 0
(-880 1550);
DISPLAY 0.617021 (-880 1550);
PAINT SKYBLUE (-880 1550);
FORCEPROP 1 LASTPIN (-925 1625) $PN 1
J 0
(-920 1587);
DISPLAY 0.617021 (-920 1587);
PAINT ORANGE (-920 1587);
FORCEPROP 1 LAST MATERIAL EMPTY
J 0
(-885 1450);
DISPLAY 0.617021 (-885 1450);
PAINT RED (-885 1450);
FORCEPROP 1 LAST PART_NUMBER G21796-026
J 0
(-885 1400);
DISPLAY 0.617021 (-885 1400);
PAINT BLUE (-885 1400);
FORCEPROP 1 LAST PACK_TYPE 0402
J 0
(-885 1350);
DISPLAY 0.617021 (-885 1350);
PAINT SKYBLUE (-885 1350);
FORCEPROP 1 LASTPIN (-925 1425) $PN 2
J 0
(-920 1435);
DISPLAY 0.617021 (-920 1435);
PAINT ORANGE (-920 1435);
FORCEPROP 1 LAST LOCATION R2N14
J 0
(-880 1650);
DISPLAY 0.617021 (-880 1650);
PAINT AQUA (-880 1650);
FORCEPROP 1 LAST VALUE 1.00K
J 0
(-880 1600);
DISPLAY 0.617021 (-880 1600);
PAINT SKYBLUE (-880 1600);
FORCEPROP 1 LAST WATTAGE 1/16W
J 0
(-885 1500);
DISPLAY 0.617021 (-885 1500);
PAINT SKYBLUE (-885 1500);
FORCEPROP 2 LAST SEC_TYPE 0402
J 0
(-875 1750);
DISPLAY 1.021277 (-875 1750);
PAINT ORANGE (-875 1750);
DISPLAY INVISIBLE (-875 1750);
FORCEPROP 2 LAST ROOM SB
J 0
(-875 1700);
DISPLAY 1.361702 (-875 1700);
PAINT ORANGE (-875 1700);
DISPLAY INVISIBLE (-875 1700);
FORCEPROP 1 LAST PATH I83
J 0
(-875 1700);
DISPLAY 0.978723 (-875 1700);
PAINT WHITE (-875 1700);
DISPLAY INVISIBLE (-875 1700);
FORCEPROP 0 LAST SEC 1
J 0
(-875 1700);
DISPLAY 0.680851 (-875 1700);
PAINT MONO (-875 1700);
DISPLAY INVISIBLE (-875 1700);
FORCEPROP 2 LAST BOM_COST SB
J 0
(-875 1700);
DISPLAY 1.361702 (-875 1700);
PAINT ORANGE (-875 1700);
DISPLAY INVISIBLE (-875 1700);
FORCEPROP 2 LAST CDS_LOCATION R2N14
J 0
(-880 1650);
DISPLAY 0.617021 (-880 1650);
PAINT AQUA (-880 1650);
DISPLAY INVISIBLE (-880 1650);
FORCEPROP 2 LAST CDS_LIB mstr_discrete
J 0
(-925 1525);
PAINT ORANGE (-925 1525);
DISPLAY INVISIBLE (-925 1525);
FORCEADD P3V3_STBY..1
(-925 1750);
FORCEPROP 3 LASTPIN (-925 1700) SIG_NAME P3V3_STBY\g
J 0
(-915 1710);
DISPLAY 0.659574 (-915 1710);
PAINT MONO (-915 1710);
DISPLAY INVISIBLE (-915 1710);
FORCEPROP 1 LAST PATH I84
J 0
(-880 1752);
DISPLAY 0.340426 (-880 1752);
PAINT GREEN (-880 1752);
DISPLAY INVISIBLE (-880 1752);
FORCEPROP 1 LAST SIZE 1B
J 0
(-880 1772);
DISPLAY 0.340426 (-880 1772);
PAINT GREEN (-880 1772);
DISPLAY INVISIBLE (-880 1772);
FORCEPROP 1 LAST VOLTAGE 3.3V
J 0
(-970 1707);
DISPLAY 0.340426 (-970 1707);
PAINT SKYBLUE (-970 1707);
DISPLAY INVISIBLE (-970 1707);
FORCEPROP 2 LAST CDS_LIB mstr_symbols
J 0
(-925 1750);
PAINT ORANGE (-925 1750);
DISPLAY INVISIBLE (-925 1750);
FORCEPROP 1 LAST BODY_TYPE PLUMBING
J 0
(-970 1707);
DISPLAY 0.340426 (-970 1707);
PAINT GREEN (-970 1707);
DISPLAY INVISIBLE (-970 1707);
FORCEPROP 1 LAST HDL_POWER P3V3_STBY
J 0
(-1225 1625);
DISPLAY 0.872340 (-1225 1625);
PAINT ORANGE (-1225 1625);
DISPLAY INVISIBLE (-1225 1625);
FORCEADD RES..2
(-5050 3775);
FORCEPROP 1 LAST VALUE 10.0K
J 0
(-4975 3825);
DISPLAY 0.617021 (-4975 3825);
PAINT SKYBLUE (-4975 3825);
FORCEPROP 1 LASTPIN (-5050 3875) $PN 1
J 0
(-5045 3837);
DISPLAY 0.617021 (-5045 3837);
PAINT WHITE (-5045 3837);
FORCEPROP 1 LASTPIN (-5050 3675) $PN 2
J 0
(-5045 3685);
DISPLAY 0.617021 (-5045 3685);
PAINT WHITE (-5045 3685);
FORCEPROP 1 LAST LOCATION R8D16
J 0
(-4975 3875);
DISPLAY 0.617021 (-4975 3875);
PAINT AQUA (-4975 3875);
FORCEPROP 1 LAST TOLERANCE 1%
J 0
(-4975 3775);
DISPLAY 0.617021 (-4975 3775);
PAINT SKYBLUE (-4975 3775);
FORCEPROP 1 LAST WATTAGE 1/16W
J 0
(-4975 3725);
DISPLAY 0.617021 (-4975 3725);
PAINT SKYBLUE (-4975 3725);
FORCEPROP 1 LAST MATERIAL CHIP
J 0
(-4975 3675);
DISPLAY 0.617021 (-4975 3675);
PAINT SKYBLUE (-4975 3675);
FORCEPROP 1 LAST PART_NUMBER G21796-016
J 0
(-4975 3625);
DISPLAY 0.617021 (-4975 3625);
PAINT BLUE (-4975 3625);
FORCEPROP 1 LAST PACK_TYPE 0402
J 0
(-4975 3575);
DISPLAY 0.617021 (-4975 3575);
PAINT SKYBLUE (-4975 3575);
FORCEPROP 2 LAST CDS_SEC 1
J 0
(-5000 4000);
DISPLAY 1.361702 (-5000 4000);
PAINT ORANGE (-5000 4000);
DISPLAY INVISIBLE (-5000 4000);
FORCEPROP 2 LAST $SEC 1
J 0
(-5000 4000);
DISPLAY 0.914894 (-5000 4000);
PAINT MONO (-5000 4000);
DISPLAY INVISIBLE (-5000 4000);
FORCEPROP 2 LAST BOM_COST SB
R 3
J 0
(-4850 3850);
PAINT ORANGE (-4850 3850);
DISPLAY INVISIBLE (-4850 3850);
FORCEPROP 2 LAST ROOM SB_HEADERS
R 3
J 0
(-4850 3850);
PAINT ORANGE (-4850 3850);
DISPLAY INVISIBLE (-4850 3850);
FORCEPROP 2 LAST CDS_LIB mstr_discrete
J 0
(-5050 3775);
PAINT ORANGE (-5050 3775);
DISPLAY INVISIBLE (-5050 3775);
FORCEPROP 1 LAST PATH I85
J 0
(-5000 3950);
DISPLAY 0.978723 (-5000 3950);
PAINT WHITE (-5000 3950);
DISPLAY INVISIBLE (-5000 3950);
FORCEPROP 2 LAST CDS_LOCATION R8D16
J 0
(-4975 3875);
DISPLAY 0.617021 (-4975 3875);
PAINT AQUA (-4975 3875);
DISPLAY INVISIBLE (-4975 3875);
FORCEADD RES..2
(-5050 3375);
FORCEPROP 1 LAST LOCATION R7D1
J 0
(-5005 3500);
DISPLAY 0.617021 (-5005 3500);
PAINT AQUA (-5005 3500);
FORCEPROP 1 LAST PACK_TYPE 0402
J 0
(-5010 3200);
DISPLAY 0.617021 (-5010 3200);
PAINT SKYBLUE (-5010 3200);
FORCEPROP 1 LASTPIN (-5050 3475) $PN 1
J 0
(-5045 3437);
DISPLAY 0.617021 (-5045 3437);
PAINT WHITE (-5045 3437);
FORCEPROP 1 LASTPIN (-5050 3275) $PN 2
J 0
(-5045 3285);
DISPLAY 0.617021 (-5045 3285);
PAINT WHITE (-5045 3285);
FORCEPROP 1 LAST TOLERANCE 1%
J 0
(-5005 3400);
DISPLAY 0.617021 (-5005 3400);
PAINT SKYBLUE (-5005 3400);
FORCEPROP 1 LAST VALUE 1.00K
J 0
(-5005 3450);
DISPLAY 0.617021 (-5005 3450);
PAINT SKYBLUE (-5005 3450);
FORCEPROP 1 LAST WATTAGE 1/16W
J 0
(-5010 3350);
DISPLAY 0.617021 (-5010 3350);
PAINT SKYBLUE (-5010 3350);
FORCEPROP 1 LAST MATERIAL EMPTY
J 0
(-5010 3300);
DISPLAY 0.617021 (-5010 3300);
PAINT RED (-5010 3300);
FORCEPROP 1 LAST PART_NUMBER G21796-026
J 0
(-5010 3250);
DISPLAY 0.617021 (-5010 3250);
PAINT BLUE (-5010 3250);
FORCEPROP 2 LAST CDS_LOCATION R7D1
J 0
(-5005 3500);
DISPLAY 0.617021 (-5005 3500);
PAINT AQUA (-5005 3500);
DISPLAY INVISIBLE (-5005 3500);
FORCEPROP 1 LAST PATH I86
J 0
(-5000 3550);
DISPLAY 0.978723 (-5000 3550);
PAINT WHITE (-5000 3550);
DISPLAY INVISIBLE (-5000 3550);
FORCEPROP 2 LAST CDS_LIB mstr_discrete
J 0
(-5050 3375);
PAINT ORANGE (-5050 3375);
DISPLAY INVISIBLE (-5050 3375);
FORCEPROP 2 LAST BOM_COST SB
J 0
(-5000 3550);
DISPLAY 1.361702 (-5000 3550);
PAINT ORANGE (-5000 3550);
DISPLAY INVISIBLE (-5000 3550);
FORCEPROP 2 LAST CDS_SEC 1
J 0
(-5000 3600);
DISPLAY 1.361702 (-5000 3600);
PAINT ORANGE (-5000 3600);
DISPLAY INVISIBLE (-5000 3600);
FORCEPROP 2 LAST $SEC 1
J 0
(-5000 3600);
DISPLAY 0.914894 (-5000 3600);
PAINT MONO (-5000 3600);
DISPLAY INVISIBLE (-5000 3600);
FORCEPROP 2 LAST ROOM SB
J 0
(-5000 3550);
DISPLAY 1.361702 (-5000 3550);
PAINT ORANGE (-5000 3550);
DISPLAY INVISIBLE (-5000 3550);
FORCEADD RES..2
(-925 4925);
FORCEPROP 1 LAST PACK_TYPE 0402
J 0
(-885 4750);
DISPLAY 0.617021 (-885 4750);
PAINT SKYBLUE (-885 4750);
FORCEPROP 1 LAST TOLERANCE 1%
J 0
(-880 4950);
DISPLAY 0.617021 (-880 4950);
PAINT SKYBLUE (-880 4950);
FORCEPROP 1 LASTPIN (-925 4825) $PN 2
J 0
(-920 4835);
DISPLAY 0.617021 (-920 4835);
PAINT ORANGE (-920 4835);
FORCEPROP 1 LASTPIN (-925 5025) $PN 1
J 0
(-920 4987);
DISPLAY 0.617021 (-920 4987);
PAINT ORANGE (-920 4987);
FORCEPROP 1 LAST MATERIAL EMPTY
J 0
(-885 4850);
DISPLAY 0.617021 (-885 4850);
PAINT RED (-885 4850);
FORCEPROP 1 LAST WATTAGE 1/16W
J 0
(-885 4900);
DISPLAY 0.617021 (-885 4900);
PAINT SKYBLUE (-885 4900);
FORCEPROP 1 LAST LOCATION R8D13
J 0
(-880 5050);
DISPLAY 0.617021 (-880 5050);
PAINT AQUA (-880 5050);
FORCEPROP 1 LAST PART_NUMBER G21796-016
J 0
(-885 4800);
DISPLAY 0.617021 (-885 4800);
PAINT BLUE (-885 4800);
FORCEPROP 1 LAST VALUE 10.0K
J 0
(-880 5000);
DISPLAY 0.617021 (-880 5000);
PAINT SKYBLUE (-880 5000);
FORCEPROP 2 LAST CDS_LOCATION R8D13
J 0
(-880 5050);
DISPLAY 0.617021 (-880 5050);
PAINT AQUA (-880 5050);
DISPLAY INVISIBLE (-880 5050);
FORCEPROP 2 LAST ROOM DB1200ZL
J 0
(-875 5150);
DISPLAY 1.021277 (-875 5150);
PAINT ORANGE (-875 5150);
DISPLAY INVISIBLE (-875 5150);
FORCEPROP 2 LAST SEC 1
J 0
(-875 5150);
DISPLAY 0.680851 (-875 5150);
PAINT MONO (-875 5150);
DISPLAY INVISIBLE (-875 5150);
FORCEPROP 2 LAST SEC_TYPE 0402
J 0
(-875 5150);
DISPLAY 1.021277 (-875 5150);
PAINT ORANGE (-875 5150);
DISPLAY INVISIBLE (-875 5150);
FORCEPROP 2 LAST BOM_COST SYS_CLOCK
J 0
(-875 5250);
DISPLAY 1.021277 (-875 5250);
PAINT ORANGE (-875 5250);
DISPLAY INVISIBLE (-875 5250);
FORCEPROP 2 LAST CDS_LIB mstr_discrete
J 0
(-925 4925);
PAINT ORANGE (-925 4925);
DISPLAY INVISIBLE (-925 4925);
FORCEPROP 1 LAST PATH I87
J 0
(-875 5100);
DISPLAY 0.978723 (-875 5100);
PAINT WHITE (-875 5100);
DISPLAY INVISIBLE (-875 5100);
FORCEADD RES..2
R 2
(-3350 1375);
FORCEPROP 1 LAST VALUE 4.75K
J 2
(-3395 1450);
DISPLAY 0.617021 (-3395 1450);
PAINT SKYBLUE (-3395 1450);
FORCEPROP 1 LAST LOCATION R2U30
J 2
(-3395 1500);
DISPLAY 0.617021 (-3395 1500);
PAINT AQUA (-3395 1500);
FORCEPROP 1 LAST TOLERANCE 1%
J 2
(-3395 1400);
DISPLAY 0.617021 (-3395 1400);
PAINT SKYBLUE (-3395 1400);
FORCEPROP 1 LASTPIN (-3350 1275) $PN 2
J 2
(-3355 1285);
DISPLAY 0.617021 (-3355 1285);
PAINT ORANGE (-3355 1285);
FORCEPROP 1 LAST PART_NUMBER G21796-072
J 2
(-3390 1250);
DISPLAY 0.617021 (-3390 1250);
PAINT BLUE (-3390 1250);
FORCEPROP 1 LAST MATERIAL EMPTY
J 2
(-3390 1300);
DISPLAY 0.617021 (-3390 1300);
PAINT RED (-3390 1300);
FORCEPROP 1 LAST WATTAGE 1/16W
J 2
(-3390 1350);
DISPLAY 0.617021 (-3390 1350);
PAINT SKYBLUE (-3390 1350);
FORCEPROP 1 LASTPIN (-3350 1475) $PN 1
J 2
(-3355 1437);
DISPLAY 0.617021 (-3355 1437);
PAINT ORANGE (-3355 1437);
FORCEPROP 1 LAST PACK_TYPE 0402
J 2
(-3390 1200);
DISPLAY 0.617021 (-3390 1200);
PAINT SKYBLUE (-3390 1200);
FORCEPROP 2 LAST CDS_LOCATION R2U30
J 2
(-3395 1500);
DISPLAY 0.617021 (-3395 1500);
PAINT AQUA (-3395 1500);
DISPLAY INVISIBLE (-3395 1500);
FORCEPROP 2 LAST SEC_TYPE 0402
J 0
(-3400 1600);
DISPLAY 1.021277 (-3400 1600);
PAINT ORANGE (-3400 1600);
DISPLAY INVISIBLE (-3400 1600);
FORCEPROP 2 LAST BOM_COST SYS_CLOCK
J 2
(-3400 1700);
DISPLAY 1.021277 (-3400 1700);
PAINT ORANGE (-3400 1700);
DISPLAY INVISIBLE (-3400 1700);
FORCEPROP 2 LAST SEC 1
J 0
(-3400 1600);
DISPLAY 0.680851 (-3400 1600);
PAINT MONO (-3400 1600);
DISPLAY INVISIBLE (-3400 1600);
FORCEPROP 2 LAST ROOM DB1200ZL
J 2
(-3400 1600);
DISPLAY 1.021277 (-3400 1600);
PAINT ORANGE (-3400 1600);
DISPLAY INVISIBLE (-3400 1600);
FORCEPROP 2 LAST CDS_LIB mstr_discrete
J 0
(-3350 1375);
PAINT MONO (-3350 1375);
DISPLAY INVISIBLE (-3350 1375);
FORCEPROP 1 LAST PATH I88
J 2
(-3400 1550);
DISPLAY 0.978723 (-3400 1550);
PAINT WHITE (-3400 1550);
DISPLAY INVISIBLE (-3400 1550);
FORCEADD RES..2
(1850 1475);
FORCEPROP 1 LAST PACK_TYPE 0402
J 0
(1890 1300);
DISPLAY 0.617021 (1890 1300);
PAINT SKYBLUE (1890 1300);
FORCEPROP 1 LASTPIN (1850 1375) $PN 2
J 0
(1855 1385);
DISPLAY 0.617021 (1855 1385);
PAINT ORANGE (1855 1385);
FORCEPROP 1 LASTPIN (1850 1575) $PN 1
J 0
(1855 1537);
DISPLAY 0.617021 (1855 1537);
PAINT ORANGE (1855 1537);
FORCEPROP 1 LAST WATTAGE 1/16W
J 0
(1890 1450);
DISPLAY 0.617021 (1890 1450);
PAINT SKYBLUE (1890 1450);
FORCEPROP 1 LAST TOLERANCE 1%
J 0
(1895 1500);
DISPLAY 0.617021 (1895 1500);
PAINT SKYBLUE (1895 1500);
FORCEPROP 1 LAST MATERIAL EMPTY
J 0
(1890 1400);
DISPLAY 0.617021 (1890 1400);
PAINT RED (1890 1400);
FORCEPROP 1 LAST PART_NUMBER G21796-026
J 0
(1890 1350);
DISPLAY 0.617021 (1890 1350);
PAINT BLUE (1890 1350);
FORCEPROP 1 LAST LOCATION R2T1
J 0
(1895 1600);
DISPLAY 0.617021 (1895 1600);
PAINT AQUA (1895 1600);
FORCEPROP 1 LAST VALUE 1.00K
J 0
(1895 1550);
DISPLAY 0.617021 (1895 1550);
PAINT SKYBLUE (1895 1550);
FORCEPROP 2 LAST CDS_LIB mstr_discrete
J 0
(1850 1475);
PAINT ORANGE (1850 1475);
DISPLAY INVISIBLE (1850 1475);
FORCEPROP 2 LAST BOM_COST SB
J 0
(1900 1650);
DISPLAY 1.361702 (1900 1650);
PAINT ORANGE (1900 1650);
DISPLAY INVISIBLE (1900 1650);
FORCEPROP 2 LAST SEC_TYPE 0402
J 0
(1900 1700);
DISPLAY 1.021277 (1900 1700);
PAINT ORANGE (1900 1700);
DISPLAY INVISIBLE (1900 1700);
FORCEPROP 2 LAST SEC 1
J 0
(1900 1700);
DISPLAY 0.680851 (1900 1700);
PAINT MONO (1900 1700);
DISPLAY INVISIBLE (1900 1700);
FORCEPROP 2 LAST ROOM SB
J 0
(1900 1650);
DISPLAY 1.361702 (1900 1650);
PAINT ORANGE (1900 1650);
DISPLAY INVISIBLE (1900 1650);
FORCEPROP 1 LAST PATH I89
J 0
(1900 1650);
DISPLAY 0.978723 (1900 1650);
PAINT WHITE (1900 1650);
DISPLAY INVISIBLE (1900 1650);
FORCEPROP 2 LAST CDS_LOCATION R2T1
J 0
(1895 1600);
DISPLAY 0.617021 (1895 1600);
PAINT AQUA (1895 1600);
DISPLAY INVISIBLE (1895 1600);
FORCEADD DNS..2
(-920 1520);
PAINT RED (-920 1520);
FORCEPROP 2 LAST CDS_LIB mstr_misc
J 0
(-920 1520);
PAINT ORANGE (-920 1520);
DISPLAY INVISIBLE (-920 1520);
FORCEPROP 1 LAST COMMENT_BODY TRUE
R 1
J 0
(-845 1295);
DISPLAY 0.872340 (-845 1295);
PAINT GREEN (-845 1295);
DISPLAY INVISIBLE (-845 1295);
FORCEADD DESIGN_NOTE..1
(-4500 3375);
FORCEPROP 0 LAST L3 GBE AUX POWER IS DISABLED WHEN LOW
J 0
(-4700 3250);
DISPLAY 1.276596 (-4700 3250);
PAINT ORANGE (-4700 3250);
FORCEPROP 0 LAST L1 GBE AUX POWER IS ENABLED WHEN HIGH (DEFAULT)
J 0
(-4700 3175);
DISPLAY 1.276596 (-4700 3175);
PAINT ORANGE (-4700 3175);
FORCEPROP 2 LAST CDS_LIB mstr_symbols
J 0
(-4500 3375);
PAINT MONO (-4500 3375);
DISPLAY INVISIBLE (-4500 3375);
FORCEPROP 1 LAST COMMENT_BODY TRUE
J 0
(-4475 3475);
DISPLAY 0.978723 (-4475 3475);
PAINT ORANGE (-4475 3475);
DISPLAY INVISIBLE (-4475 3475);
FORCEADD DESIGN_NOTE..1
(-2200 1150);
FORCEPROP 0 LAST L3 BOOT LPC/ESPI WHEN HIGH
J 0
(-2375 950);
DISPLAY 1.276596 (-2375 950);
PAINT ORANGE (-2375 950);
FORCEPROP 0 LAST L1 PCH HAS INTERNAL PULL-DOWN
J 0
(-2375 875);
DISPLAY 1.319149 (-2375 875);
PAINT WHITE (-2375 875);
FORCEPROP 0 LAST L2 BOOT SPI WHEN LOW (DEFAULT)
J 0
(-2375 1025);
DISPLAY 1.276596 (-2375 1025);
PAINT ORANGE (-2375 1025);
FORCEPROP 2 LAST BOM_COST SB
J 0
(-2075 1050);
DISPLAY 1.361702 (-2075 1050);
PAINT ORANGE (-2075 1050);
DISPLAY INVISIBLE (-2075 1050);
FORCEPROP 2 LAST ROOM SB_HEADERS
J 0
(-2075 1050);
DISPLAY 1.361702 (-2075 1050);
PAINT ORANGE (-2075 1050);
DISPLAY INVISIBLE (-2075 1050);
FORCEPROP 2 LAST CDS_LIB mstr_symbols
J 0
(-2200 1150);
PAINT ORANGE (-2200 1150);
DISPLAY INVISIBLE (-2200 1150);
FORCEPROP 1 LAST COMMENT_BODY TRUE
J 0
(-2175 1250);
DISPLAY 1.319149 (-2175 1250);
PAINT ORANGE (-2175 1250);
DISPLAY INVISIBLE (-2175 1250);
FORCEADD DNS..2
(-5045 3370);
PAINT RED (-5045 3370);
FORCEPROP 2 LAST CDS_LIB mstr_misc
J 0
(-5045 3370);
PAINT ORANGE (-5045 3370);
DISPLAY INVISIBLE (-5045 3370);
FORCEPROP 1 LAST COMMENT_BODY TRUE
R 1
J 0
(-4970 3145);
DISPLAY 0.872340 (-4970 3145);
PAINT GREEN (-4970 3145);
DISPLAY INVISIBLE (-4970 3145);
FORCEADD DNS..2
(405 4595);
PAINT RED (405 4595);
FORCEPROP 2 LAST CDS_LIB mstr_misc
J 0
(405 4595);
PAINT ORANGE (405 4595);
DISPLAY INVISIBLE (405 4595);
FORCEPROP 1 LAST COMMENT_BODY TRUE
R 1
J 0
(480 4370);
DISPLAY 0.872340 (480 4370);
PAINT GREEN (480 4370);
DISPLAY INVISIBLE (480 4370);
FORCEADD DESIGN_NOTE..1
(-2250 4100);
FORCEPROP 0 LAST L2 ADR TIMER HOLD OFF DISABLED WHEN HIGH (DEFAULT)
J 0
(-2425 3975);
DISPLAY 1.276596 (-2425 3975);
PAINT ORANGE (-2425 3975);
FORCEPROP 0 LAST L3 ADR TIMER HOLD OFF ENABLED WHEN LOW
J 0
(-2425 3900);
DISPLAY 1.276596 (-2425 3900);
PAINT ORANGE (-2425 3900);
FORCEPROP 0 LAST L1 LBG EDS R1.0: PCH INTERNAL PU 0108
J 0
(-2425 3825);
DISPLAY 1.276596 (-2425 3825);
PAINT RED (-2425 3825);
FORCEPROP 2 LAST CDS_LIB mstr_symbols
J 0
(-2250 4100);
PAINT ORANGE (-2250 4100);
DISPLAY INVISIBLE (-2250 4100);
FORCEPROP 2 LAST ROOM SB_HEADERS
J 0
(-2125 4000);
DISPLAY 1.361702 (-2125 4000);
PAINT ORANGE (-2125 4000);
DISPLAY INVISIBLE (-2125 4000);
FORCEPROP 2 LAST BOM_COST SB
J 0
(-2125 4000);
DISPLAY 1.361702 (-2125 4000);
PAINT ORANGE (-2125 4000);
DISPLAY INVISIBLE (-2125 4000);
FORCEPROP 1 LAST COMMENT_BODY TRUE
J 0
(-2225 4200);
DISPLAY 1.319149 (-2225 4200);
PAINT ORANGE (-2225 4200);
DISPLAY INVISIBLE (-2225 4200);
FORCEADD DESIGN_NOTE..1
(50 1250);
FORCEPROP 0 LAST L1 PCH INTERNAL PULL-UP.
J 0
(-125 950);
DISPLAY 1.319149 (-125 950);
PAINT WHITE (-125 950);
FORCEPROP 0 LAST L3 PERSONALITY STRAP DISABLE WHEN HIGH
J 0
(-125 1025);
DISPLAY 1.361702 (-125 1025);
PAINT ORANGE (-125 1025);
FORCEPROP 0 LAST L2 PERSONALITY STRAP ENABLE WHEN LOW (DEFAULT)
J 0
(-125 1100);
DISPLAY 1.319149 (-125 1100);
PAINT WHITE (-125 1100);
FORCEPROP 2 LAST CDS_LIB mstr_symbols
J 0
(50 1250);
PAINT ORANGE (50 1250);
DISPLAY INVISIBLE (50 1250);
FORCEPROP 2 LAST BOM_COST SB
J 0
(-125 1150);
DISPLAY 1.361702 (-125 1150);
PAINT ORANGE (-125 1150);
DISPLAY INVISIBLE (-125 1150);
FORCEPROP 2 LAST ROOM SB
J 0
(-125 1150);
DISPLAY 1.361702 (-125 1150);
PAINT ORANGE (-125 1150);
DISPLAY INVISIBLE (-125 1150);
FORCEPROP 1 LAST COMMENT_BODY TRUE
J 0
(75 1350);
DISPLAY 1.319149 (75 1350);
PAINT ORANGE (75 1350);
DISPLAY INVISIBLE (75 1350);
FORCEADD DNS..2
(-3345 1395);
PAINT RED (-3345 1395);
FORCEPROP 2 LAST CDS_LIB mstr_misc
J 0
(-3345 1395);
PAINT MONO (-3345 1395);
DISPLAY INVISIBLE (-3345 1395);
FORCEPROP 1 LAST COMMENT_BODY TRUE
R 1
J 0
(-3270 1170);
DISPLAY 0.872340 (-3270 1170);
PAINT GREEN (-3270 1170);
DISPLAY INVISIBLE (-3270 1170);
FORCEADD DNS..2
(-945 3145);
PAINT RED (-945 3145);
FORCEPROP 2 LAST CDS_LIB mstr_misc
J 0
(-945 3145);
PAINT ORANGE (-945 3145);
DISPLAY INVISIBLE (-945 3145);
FORCEPROP 1 LAST COMMENT_BODY TRUE
R 1
J 0
(-870 2920);
DISPLAY 0.872340 (-870 2920);
PAINT GREEN (-870 2920);
DISPLAY INVISIBLE (-870 2920);
FORCEADD DESIGN_NOTE..1
(-5050 2200);
FORCEPROP 0 LAST L2 TLS ENABLED WHEN HIGH (DEFAULT)
J 0
(-5250 2050);
DISPLAY 1.319149 (-5250 2050);
PAINT WHITE (-5250 2050);
FORCEPROP 0 LAST L3 TLS DISABLED WHEN LOW
J 0
(-5250 1975);
DISPLAY 1.276596 (-5250 1975);
PAINT ORANGE (-5250 1975);
FORCEPROP 0 LAST L1 PCH INTERNAL PULL-DOWN.
J 0
(-5250 1900);
DISPLAY 1.319149 (-5250 1900);
PAINT WHITE (-5250 1900);
FORCEPROP 2 LAST CDS_LIB mstr_symbols
J 0
(-5050 2200);
PAINT ORANGE (-5050 2200);
DISPLAY INVISIBLE (-5050 2200);
FORCEPROP 2 LAST BOM_COST SB
J 0
(-5225 2100);
DISPLAY 1.361702 (-5225 2100);
PAINT ORANGE (-5225 2100);
DISPLAY INVISIBLE (-5225 2100);
FORCEPROP 2 LAST ROOM SB
J 0
(-5225 2100);
DISPLAY 1.361702 (-5225 2100);
PAINT ORANGE (-5225 2100);
DISPLAY INVISIBLE (-5225 2100);
FORCEPROP 1 LAST COMMENT_BODY TRUE
J 0
(-5025 2300);
DISPLAY 1.319149 (-5025 2300);
PAINT ORANGE (-5025 2300);
DISPLAY INVISIBLE (-5025 2300);
FORCEADD DNS..2
(1755 3045);
PAINT RED (1755 3045);
FORCEPROP 2 LAST CDS_LIB mstr_misc
J 0
(1755 3045);
PAINT ORANGE (1755 3045);
DISPLAY INVISIBLE (1755 3045);
FORCEPROP 1 LAST COMMENT_BODY TRUE
R 1
J 0
(1830 2820);
DISPLAY 0.872340 (1830 2820);
PAINT GREEN (1830 2820);
DISPLAY INVISIBLE (1830 2820);
FORCEADD DNS..2
(-920 4445);
PAINT RED (-920 4445);
FORCEPROP 2 LAST CDS_LIB mstr_misc
J 0
(-920 4445);
PAINT ORANGE (-920 4445);
DISPLAY INVISIBLE (-920 4445);
FORCEPROP 1 LAST COMMENT_BODY TRUE
R 1
J 0
(-845 4220);
DISPLAY 0.872340 (-845 4220);
PAINT GREEN (-845 4220);
DISPLAY INVISIBLE (-845 4220);
FORCEADD DESIGN_NOTE..1
(-5000 1025);
FORCEPROP 0 LAST L1 PCH INTERNAL PULL-DOWN.
J 0
(-5200 725);
DISPLAY 1.319149 (-5200 725);
PAINT WHITE (-5200 725);
FORCEPROP 0 LAST L4 NORMAL UV ADR TRIGGER ENABLE FUNCTIONALITY RESUMES AFTER PLTRST# DEASSERTS
J 0
(-5200 675);
DISPLAY 0.808511 (-5200 675);
PAINT ORANGE (-5200 675);
FORCEPROP 0 LAST L3 NO REBOOT DISABLED WHEN LOW (DEFAULT)
J 0
(-5200 800);
DISPLAY 1.276596 (-5200 800);
PAINT ORANGE (-5200 800);
FORCEPROP 0 LAST L2 NO REBOOT ENABLED WHEN HIGH
J 0
(-5200 875);
DISPLAY 1.319149 (-5200 875);
PAINT WHITE (-5200 875);
FORCEPROP 2 LAST CDS_LIB mstr_symbols
J 0
(-5000 1025);
PAINT ORANGE (-5000 1025);
DISPLAY INVISIBLE (-5000 1025);
FORCEPROP 2 LAST BOM_COST SB
J 0
(-5175 925);
DISPLAY 1.361702 (-5175 925);
PAINT ORANGE (-5175 925);
DISPLAY INVISIBLE (-5175 925);
FORCEPROP 2 LAST ROOM SB
J 0
(-5175 925);
DISPLAY 1.361702 (-5175 925);
PAINT ORANGE (-5175 925);
DISPLAY INVISIBLE (-5175 925);
FORCEPROP 1 LAST COMMENT_BODY TRUE
J 0
(-4975 1125);
DISPLAY 1.319149 (-4975 1125);
PAINT ORANGE (-4975 1125);
DISPLAY INVISIBLE (-4975 1125);
FORCEADD DESIGN_NOTE..1
(175 2850);
FORCEPROP 0 LAST L1 PCH INTERNAL PULL-UP.
J 0
(0 2550);
DISPLAY 1.319149 (0 2550);
PAINT WHITE (0 2550);
FORCEPROP 0 LAST L3 CONSENT STRAP ENABLED WHEN LOW
J 0
(0 2700);
DISPLAY 1.361702 (0 2700);
PAINT ORANGE (0 2700);
FORCEPROP 0 LAST L2 CONSENT STRAP DISABLED WHEN HIGH (DEFAULT)
J 0
(0 2625);
DISPLAY 1.319149 (0 2625);
PAINT WHITE (0 2625);
FORCEPROP 2 LAST CDS_LIB mstr_symbols
J 0
(175 2850);
PAINT ORANGE (175 2850);
DISPLAY INVISIBLE (175 2850);
FORCEPROP 2 LAST BOM_COST SB
J 0
(0 2750);
DISPLAY 1.361702 (0 2750);
PAINT ORANGE (0 2750);
DISPLAY INVISIBLE (0 2750);
FORCEPROP 2 LAST ROOM SB
J 0
(0 2750);
DISPLAY 1.361702 (0 2750);
PAINT ORANGE (0 2750);
DISPLAY INVISIBLE (0 2750);
FORCEPROP 1 LAST COMMENT_BODY TRUE
J 0
(200 2950);
DISPLAY 1.319149 (200 2950);
PAINT ORANGE (200 2950);
DISPLAY INVISIBLE (200 2950);
FORCEADD DNS..2
(-920 4920);
PAINT RED (-920 4920);
FORCEPROP 2 LAST CDS_LIB mstr_misc
J 0
(-920 4920);
PAINT ORANGE (-920 4920);
DISPLAY INVISIBLE (-920 4920);
FORCEPROP 1 LAST COMMENT_BODY TRUE
R 1
J 0
(-845 4695);
DISPLAY 0.872340 (-845 4695);
PAINT GREEN (-845 4695);
DISPLAY INVISIBLE (-845 4695);
FORCEADD DNS..2
(-3270 4970);
PAINT RED (-3270 4970);
FORCEPROP 2 LAST CDS_LIB mstr_misc
J 0
(-3270 4970);
PAINT ORANGE (-3270 4970);
DISPLAY INVISIBLE (-3270 4970);
FORCEPROP 1 LAST COMMENT_BODY TRUE
R 1
J 0
(-3195 4745);
DISPLAY 0.872340 (-3195 4745);
PAINT GREEN (-3195 4745);
DISPLAY INVISIBLE (-3195 4745);
FORCEADD DESIGN_NOTE..1
(-2250 2500);
FORCEPROP 0 LAST L1 PCH INTERNAL PULL-UP.
J 0
(-2425 2200);
DISPLAY 1.319149 (-2425 2200);
PAINT WHITE (-2425 2200);
FORCEPROP 0 LAST L3 BOOT HALT ENABLED WHEN LOW
J 0
(-2425 2350);
DISPLAY 1.361702 (-2425 2350);
PAINT ORANGE (-2425 2350);
FORCEPROP 0 LAST L2 BOOT HALT DISABLE WHEN HIGH (DEFAULT)
J 0
(-2425 2275);
DISPLAY 1.319149 (-2425 2275);
PAINT WHITE (-2425 2275);
FORCEPROP 2 LAST BOM_COST SB
J 0
(-2425 2400);
DISPLAY 1.361702 (-2425 2400);
PAINT ORANGE (-2425 2400);
DISPLAY INVISIBLE (-2425 2400);
FORCEPROP 2 LAST CDS_LIB mstr_symbols
J 0
(-2250 2500);
PAINT ORANGE (-2250 2500);
DISPLAY INVISIBLE (-2250 2500);
FORCEPROP 2 LAST ROOM SB
J 0
(-2425 2400);
DISPLAY 1.361702 (-2425 2400);
PAINT ORANGE (-2425 2400);
DISPLAY INVISIBLE (-2425 2400);
FORCEPROP 1 LAST COMMENT_BODY TRUE
J 0
(-2225 2600);
DISPLAY 1.319149 (-2225 2600);
PAINT ORANGE (-2225 2600);
DISPLAY INVISIBLE (-2225 2600);
FORCEADD DNS..2
(1855 1495);
PAINT RED (1855 1495);
FORCEPROP 2 LAST CDS_LIB mstr_misc
J 0
(1855 1495);
PAINT ORANGE (1855 1495);
DISPLAY INVISIBLE (1855 1495);
FORCEPROP 1 LAST COMMENT_BODY TRUE
R 1
J 0
(1930 1270);
DISPLAY 0.872340 (1930 1270);
PAINT GREEN (1930 1270);
DISPLAY INVISIBLE (1930 1270);
FORCEADD DNS..2
(1855 1870);
PAINT RED (1855 1870);
FORCEPROP 2 LAST CDS_LIB mstr_misc
J 0
(1855 1870);
PAINT ORANGE (1855 1870);
DISPLAY INVISIBLE (1855 1870);
FORCEPROP 1 LAST COMMENT_BODY TRUE
R 1
J 0
(1930 1645);
DISPLAY 0.872340 (1930 1645);
PAINT GREEN (1930 1645);
DISPLAY INVISIBLE (1930 1645);
FORCEADD DNS..2
(-3220 2195);
PAINT RED (-3220 2195);
FORCEPROP 2 LAST CDS_LIB mstr_misc
J 0
(-3220 2195);
PAINT ORANGE (-3220 2195);
DISPLAY INVISIBLE (-3220 2195);
FORCEPROP 1 LAST COMMENT_BODY TRUE
R 1
J 0
(-3145 1970);
DISPLAY 0.872340 (-3145 1970);
PAINT GREEN (-3145 1970);
DISPLAY INVISIBLE (-3145 1970);
FORCEADD DESIGN_NOTE..1
(50 4150);
FORCEPROP 0 LAST L2 FLASH DESC OVERRIDE ENABLED WHEN LOW (DEFAULT)
J 0
(-125 3925);
DISPLAY 1.319149 (-125 3925);
PAINT WHITE (-125 3925);
FORCEPROP 0 LAST L3 FLASH DESC OVERRIDE DISABLED WHEN HIGH
J 0
(-125 4000);
DISPLAY 1.361702 (-125 4000);
PAINT ORANGE (-125 4000);
FORCEPROP 0 LAST L1 PCH INTERNAL PULL-DOWN.
J 0
(-125 3850);
DISPLAY 1.319149 (-125 3850);
PAINT WHITE (-125 3850);
FORCEPROP 2 LAST CDS_LIB mstr_symbols
J 0
(50 4150);
PAINT MONO (50 4150);
DISPLAY INVISIBLE (50 4150);
FORCEPROP 2 LAST BOM_COST SB
J 0
(-125 4050);
DISPLAY 1.361702 (-125 4050);
PAINT ORANGE (-125 4050);
DISPLAY INVISIBLE (-125 4050);
FORCEPROP 2 LAST ROOM SB
J 0
(-125 4050);
DISPLAY 1.361702 (-125 4050);
PAINT ORANGE (-125 4050);
DISPLAY INVISIBLE (-125 4050);
FORCEPROP 1 LAST COMMENT_BODY TRUE
J 0
(75 4250);
DISPLAY 1.319149 (75 4250);
PAINT ORANGE (75 4250);
DISPLAY INVISIBLE (75 4250);
FORCEADD DNS..2
(-945 2745);
PAINT RED (-945 2745);
FORCEPROP 2 LAST CDS_LIB mstr_misc
J 0
(-945 2745);
PAINT ORANGE (-945 2745);
DISPLAY INVISIBLE (-945 2745);
FORCEPROP 1 LAST COMMENT_BODY TRUE
R 1
J 0
(-870 2520);
DISPLAY 0.872340 (-870 2520);
PAINT GREEN (-870 2520);
DISPLAY INVISIBLE (-870 2520);
FORCEADD INTEL_CORP_BPAGE..1
(2650 500);
FORCEPROP 1 LAST CDS_CON_LAST_MODIFIED Fri Jun 16 17:48:48 2017
J 0
(1225 825);
PAINT ORANGE (1225 825);
DISPLAY INVISIBLE (1225 825);
FORCEPROP 1 LAST CUSTOM_TXT_CDS <CURRENT_DESIGN_SHEET> OF <TOTAL_DESIGN_SHEETS>
J 0
(2150 525);
PAINT ORANGE (2150 525);
FORCEPROP 1 LAST CUSTOM_TXT_CDS <CON_LAST_MODIFIED>
J 0
(-1350 600);
PAINT ORANGE (-1350 600);
FORCEPROP 2 LAST CUSTOM_TXT_CDS <XR_PAGE_TITLE>
J 0
(-5240 5750);
DISPLAY 0.638298 (-5240 5750);
PAINT PINK (-5240 5750);
DISPLAY INVISIBLE (-5240 5750);
FORCEPROP 1 LAST SCH_TITLE PCH STRAPS (1/2)
J 0
(-5300 550);
DISPLAY 1.212766 (-5300 550);
PAINT ORANGE (-5300 550);
FORCEPROP 2 LAST CDS_LIB mstr_symbols
J 0
(2650 500);
PAINT MONO (2650 500);
DISPLAY INVISIBLE (2650 500);
FORCEPROP 2 LAST BOM_COST ST_SATA
J 0
(-5225 5800);
PAINT MONO (-5225 5800);
DISPLAY INVISIBLE (-5225 5800);
FORCEPROP 2 LAST PAGE_BORDER TRUE
J 0
(-5240 5750);
DISPLAY 0.851064 (-5240 5750);
PAINT PINK (-5240 5750);
DISPLAY INVISIBLE (-5240 5750);
FORCEPROP 1 LAST COMMENT_BODY TRUE
J 0
(2662 512);
DISPLAY 0.468085 (2662 512);
PAINT GREEN (2662 512);
DISPLAY INVISIBLE (2662 512);
FORCEPROP 2 LAST CDS_XR_PAGE_TITLE CR-125 : @BASEBOARD_FAB2_LIB.BASEBOARD_FAB2(SCH_1):PAGE125
J 0
(-5240 5750);
DISPLAY 0.638298 (-5240 5750);
PAINT PINK (-5240 5750);
DISPLAY INVISIBLE (-5240 5750);
FORCEADD DESIGN_NOTE..1
(-5025 4650);
FORCEPROP 0 LAST L2 PCH HAS INTERNAL PULL-DOWN
J 0
(-5225 4375);
DISPLAY 1.276596 (-5225 4375);
PAINT ORANGE (-5225 4375);
FORCEPROP 0 LAST L1 GBE DEBUG MODE IS ENABLED WHEN HIGH
J 0
(-5225 4450);
DISPLAY 1.319149 (-5225 4450);
PAINT WHITE (-5225 4450);
FORCEPROP 0 LAST L3 GBE DEBUG MODE IS DISABLED WHEN LOW (DEFAULT)
J 0
(-5225 4525);
DISPLAY 1.276596 (-5225 4525);
PAINT ORANGE (-5225 4525);
FORCEPROP 2 LAST CDS_LIB mstr_symbols
J 0
(-5025 4650);
PAINT ORANGE (-5025 4650);
DISPLAY INVISIBLE (-5025 4650);
FORCEPROP 2 LAST BOM_COST SB
J 0
(-5200 4550);
DISPLAY 1.361702 (-5200 4550);
PAINT ORANGE (-5200 4550);
DISPLAY INVISIBLE (-5200 4550);
FORCEPROP 2 LAST ROOM SB
J 0
(-5200 4550);
DISPLAY 1.361702 (-5200 4550);
PAINT ORANGE (-5200 4550);
DISPLAY INVISIBLE (-5200 4550);
FORCEPROP 1 LAST COMMENT_BODY TRUE
J 0
(-5000 4750);
DISPLAY 1.319149 (-5000 4750);
PAINT ORANGE (-5000 4750);
DISPLAY INVISIBLE (-5000 4750);
WIRE 16 -1 (1750 2950)(1750 2850);
WIRE 16 -1 (1850 1375)(1850 1275);
WIRE 16 -1 (-950 2650)(-950 2550);
WIRE 16 -1 (-950 3325)(-950 3250);
WIRE 16 -1 (-3225 2700)(-3225 2625);
WIRE 16 -1 (-925 5050)(-925 5025);
WIRE 16 -1 (-925 4350)(-925 4250);
WIRE 16 -1 (-3225 2100)(-3225 2050);
WIRE 16 -1 (-3275 5150)(-3275 5075);
WIRE 16 -1 (-5050 3925)(-5050 3875);
WIRE 16 -1 (-5050 3275)(-5050 3225);
WIRE 16 -1 (400 4700)(400 4850);
WIRE 16 -1 (-3350 1475)(-3350 1550);
WIRE 16 -1 (1850 1975)(1850 2075);
WIRE 16 -1 (-925 1625)(-925 1700);
WIRE 16 273 (-2600 1825)(-5275 1825);
WIRE 16 273 (-2600 550)(-2600 1825);
WIRE 16 273 (-2600 1825)(-2600 2100);
WIRE 16 273 (-225 3775)(-225 5450);
WIRE 16 273 (-225 3775)(2600 3775);
WIRE 16 273 (-225 825)(-225 2100);
WIRE 16 273 (-2600 2100)(-225 2100);
WIRE 16 273 (-225 2100)(-225 3750);
WIRE 16 273 (-225 3750)(-225 3775);
WIRE 16 273 (-2600 3050)(-5225 3050);
WIRE 16 273 (-2600 3050)(-2600 2100);
WIRE 16 273 (-5275 4300)(-2600 4300);
WIRE 16 273 (-2600 4300)(-2600 5400);
WIRE 16 273 (-2600 3050)(-2600 3750);
WIRE 16 273 (-2600 3750)(-225 3750);
WIRE 16 273 (-2600 3750)(-2600 4300);
WIRE 16 -1 (-925 1350)(-1925 1350);
FORCEPROP 0 LAST SIG_NAME FM_USB_P0_EN_BOOT_BIOS_STRAP_N
J 0
(-1785 1360);
DISPLAY 0.617021 (-1785 1360);
PAINT ORANGE (-1785 1360);
WIRE 16 -1 (-925 1350)(-925 1425);
WIRE 16 -1 (1750 3150)(1750 3275);
WIRE 16 -1 (700 3275)(1750 3275);
FORCEPROP 0 LAST SIG_NAME SPI_PCH_IO2
J 0
(850 3285);
DISPLAY 0.617021 (850 3285);
PAINT ORANGE (850 3285);
WIRE 16 -1 (-3225 2300)(-3225 2350);
WIRE 16 -1 (-3225 2350)(-3225 2425);
WIRE 16 -1 (-4175 2350)(-3225 2350);
FORCEPROP 0 LAST SIG_NAME PU_PCH_TLS_ENABLE_STRAP
J 2
(-3360 2360);
DISPLAY 0.617021 (-3360 2360);
PAINT ORANGE (-3360 2360);
WIRE 16 -1 (-3350 1175)(-4025 1175);
FORCEPROP 2 LAST SIG_NAME FM_UV_ADR_TRIGGER_EN
J 0
(-3985 1185);
DISPLAY 0.617021 (-3985 1185);
PAINT ORANGE (-3985 1185);
WIRE 16 -1 (-3350 1175)(-3350 1275);
WIRE 16 -1 (400 4325)(400 4500);
WIRE 16 -1 (400 4325)(1500 4325);
FORCEPROP 2 LAST SIG_NAME FM_FLASH_DESC_OVERRIDE
J 0
(915 4335);
DISPLAY 0.617021 (915 4335);
PAINT ORANGE (915 4335);
WIRE 16 -1 (-3275 4800)(-3275 4875);
WIRE 16 -1 (-4025 4800)(-3275 4800);
FORCEPROP 2 LAST SIG_NAME RMII_BMC_PCH_SPRNGVLLE_RXER
J 0
(-4035 4810);
DISPLAY 0.617021 (-4035 4810);
PAINT ORANGE (-4035 4810);
WIRE 16 -1 (-950 2850)(-950 2975);
WIRE 16 -1 (-950 2975)(-950 3050);
WIRE 16 -1 (-1400 2975)(-950 2975);
FORCEPROP 0 LAST SIG_NAME SPI_PCH_MOSI
J 0
(-1375 2985);
DISPLAY 0.617021 (-1375 2985);
PAINT ORANGE (-1375 2985);
WIRE 16 -1 (-1750 4675)(-925 4675);
FORCEPROP 0 LAST SIG_NAME PU_ADR_TIMER_HOLD_OFF_N
J 0
(-1735 4685);
DISPLAY 0.617021 (-1735 4685);
PAINT ORANGE (-1735 4685);
WIRE 16 -1 (-925 4825)(-925 4675);
WIRE 16 -1 (-925 4550)(-925 4675);
WIRE 16 -1 (-5050 3475)(-5050 3575);
WIRE 16 -1 (-3900 3575)(-5050 3575);
FORCEPROP 0 LAST SIG_NAME RMII_PCH_SPRNGVLLE_ARB_OUT
J 0
(-4685 3585);
DISPLAY 0.617021 (-4685 3585);
PAINT ORANGE (-4685 3585);
WIRE 16 -1 (-5050 3675)(-5050 3575);
WIRE 16 273 (-200 2475)(2625 2475);
WIRE 16 -1 (1850 1575)(1850 1700);
WIRE 16 -1 (1850 1700)(1850 1775);
WIRE 16 -1 (975 1700)(1850 1700);
FORCEPROP 0 LAST SIG_NAME SPI_PCH_IO3
J 0
(1125 1710);
DISPLAY 0.617021 (1125 1710);
PAINT ORANGE (1125 1710);
DOT 1 (-5050 3575);
DOT 1 (-950 2975);
DOT 1 (-225 2100);
DOT 1 (-225 3750);
DOT 1 (-225 3775);
DOT 1 (-2600 4300);
DOT 1 (-925 4675);
DOT 1 (1850 1700);
DOT 1 (-3225 2350);
DOT 1 (-2600 3050);
DOT 1 (-2600 2100);
DOT 1 (-2600 1825);
DOT 1 (-2600 3750);
FORCENOTE
1
(-3000 3850) 0;
DISPLAY LEFT (-3000 3850);
DISPLAY 8.255319 (-3000 3850);
PAINT PURPLE (-3000 3850);
FORCENOTE
GBE DEBUG ENABLE
(-5275 5225) 0;
DISPLAY LEFT (-5275 5225);
DISPLAY 2.680851 (-5275 5225);
PAINT PURPLE (-5275 5225);
FORCENOTE
TP FAB1 NOPOP RES 0106
(-3525 4725) 0;
DISPLAY LEFT (-3525 4725);
DISPLAY 1.021277 (-3525 4725);
PAINT RED (-3525 4725);
FORCENOTE
BOOT HALT
(-2500 3525) 0;
DISPLAY LEFT (-2500 3525);
DISPLAY 2.680851 (-2500 3525);
PAINT PURPLE (-2500 3525);
FORCENOTE
NO REBOOT
(-5225 1625) 0;
DISPLAY LEFT (-5225 1625);
DISPLAY 2.680851 (-5225 1625);
PAINT PURPLE (-5225 1625);
FORCENOTE
ADR TIMER OFF
(-2500 5275) 0;
DISPLAY LEFT (-2500 5275);
DISPLAY 2.680851 (-2500 5275);
PAINT PURPLE (-2500 5275);
FORCENOTE
FLASH DESCRIPTOR
(-150 5300) 0;
DISPLAY LEFT (-150 5300);
DISPLAY 2.680851 (-150 5300);
PAINT PURPLE (-150 5300);
FORCENOTE
OVERRIDE
(-125 5150) 0;
DISPLAY LEFT (-125 5150);
DISPLAY 2.680851 (-125 5150);
PAINT PURPLE (-125 5150);
FORCENOTE
1
(2275 3275) 0;
DISPLAY LEFT (2275 3275);
DISPLAY 8.255319 (2275 3275);
PAINT PURPLE (2275 3275);
FORCENOTE
BOM_COST=SB
(1725 5150) 0;
DISPLAY LEFT (1725 5150);
DISPLAY 1.723404 (1725 5150);
PAINT PURPLE (1725 5150);
FORCENOTE
ROOM=SB
(1975 5300) 0;
DISPLAY LEFT (1975 5300);
DISPLAY 1.723404 (1975 5300);
PAINT PURPLE (1975 5300);
FORCENOTE
1
(-575 5025) 0;
DISPLAY LEFT (-575 5025);
DISPLAY 8.255319 (-575 5025);
PAINT PURPLE (-575 5025);
FORCENOTE
GBE AUX POWER
(-5250 4100) 0;
DISPLAY LEFT (-5250 4100);
DISPLAY 2.680851 (-5250 4100);
PAINT PURPLE (-5250 4100);
FORCENOTE
TP FAB1 NOPOP R2U30 0111
(-3750 1075) 0;
DISPLAY LEFT (-3750 1075);
DISPLAY 1.021277 (-3750 1075);
PAINT RED (-3750 1075);
FORCENOTE
0
(-2975 1350) 0;
DISPLAY LEFT (-2975 1350);
DISPLAY 8.255319 (-2975 1350);
PAINT PURPLE (-2975 1350);
FORCENOTE
TP FAB1 NOPOP RES 0108
(-2050 5000) 0;
DISPLAY LEFT (-2050 5000);
DISPLAY 1.021277 (-2050 5000);
PAINT RED (-2050 5000);
FORCENOTE
0
(-2975 5050) 0;
DISPLAY LEFT (-2975 5050);
DISPLAY 8.255319 (-2975 5050);
PAINT PURPLE (-2975 5050);
FORCENOTE
TP FAB1 SET TO 1
(-4700 3850) 0;
DISPLAY LEFT (-4700 3850);
DISPLAY 1.021277 (-4700 3850);
PAINT RED (-4700 3850);
FORCENOTE
(TP FAB1 NOT INTERNAL PD 0203)
(-4700 3100) 0;
DISPLAY LEFT (-4700 3100);
DISPLAY 1.021277 (-4700 3100);
PAINT RED (-4700 3100);
FORCENOTE
TLS CONFIDENTIALITY
(-5275 2850) 0;
DISPLAY LEFT (-5275 2850);
DISPLAY 2.680851 (-5275 2850);
PAINT PURPLE (-5275 2850);
FORCENOTE
1
(-2950 2625) 0;
DISPLAY LEFT (-2950 2625);
DISPLAY 8.255319 (-2950 2625);
PAINT PURPLE (-2950 2625);
FORCENOTE
1
(-625 3300) 0;
DISPLAY LEFT (-625 3300);
DISPLAY 8.255319 (-625 3300);
PAINT PURPLE (-625 3300);
FORCENOTE
BOOT BIOS DEVICE
(-2475 1900) 0;
DISPLAY LEFT (-2475 1900);
DISPLAY 2.680851 (-2475 1900);
PAINT PURPLE (-2475 1900);
FORCENOTE
PERSONALITY STRAP
(-125 2300) 0;
DISPLAY LEFT (-125 2300);
DISPLAY 2.680851 (-125 2300);
PAINT PURPLE (-125 2300);
FORCENOTE
0
(2250 2025) 0;
DISPLAY LEFT (2250 2025);
DISPLAY 8.255319 (2250 2025);
PAINT PURPLE (2250 2025);
FORCENOTE
TP FAB1 NOPOP RES 20160421
(750 1350) 0;
DISPLAY LEFT (750 1350);
DISPLAY 1.021277 (750 1350);
PAINT RED (750 1350);
FORCENOTE
CONSENT STRAP 
(125 3575) 0;
DISPLAY LEFT (125 3575);
DISPLAY 2.680851 (125 3575);
PAINT PURPLE (125 3575);
FORCENOTE
0
(-550 1675) 0;
DISPLAY LEFT (-550 1675);
DISPLAY 8.255319 (-550 1675);
PAINT PURPLE (-550 1675);
FORCENOTE
0
(2250 3950) 0;
DISPLAY LEFT (2250 3950);
DISPLAY 8.255319 (2250 3950);
PAINT PURPLE (2250 3950);
QUIT
